FILE_TYPE = MACRO_DRAWING;
SET COLOR_WIRE YELLOW;
SET COLOR_PROP MONO;
SET COLOR_DOT WHITE;
SET COLOR_ARC YELLOW;
SET COLOR_BODY GREEN;
SET COLOR_NOTE MONO;
SET PROP_DISPLAY VALUE;
SET PAGE_NUMBER P232;
FORCEADD CAP..1
(-8600 875);
FORCEPROP 1 LAST VOLTAGE 4V
J 0
(-8550 875);
DISPLAY 0.638298 (-8550 875);
PAINT SKYBLUE (-8550 875);
FORCEPROP 1 LAST TOLERANCE 20%
J 0
(-8550 825);
DISPLAY 0.617021 (-8550 825);
PAINT SKYBLUE (-8550 825);
FORCEPROP 1 LASTPIN (-8600 775) $PN 2
J 0
(-8590 755);
DISPLAY 0.617021 (-8590 755);
PAINT GREEN (-8590 755);
FORCEPROP 1 LASTPIN (-8600 975) $PN 1
J 0
(-8590 955);
DISPLAY 0.617021 (-8590 955);
PAINT GREEN (-8590 955);
FORCEPROP 1 LAST MATERIAL X6S
J 0
(-8550 775);
DISPLAY 0.617021 (-8550 775);
PAINT SKYBLUE (-8550 775);
FORCEPROP 1 LAST PACK_TYPE 0603LF
J 0
(-8550 675);
DISPLAY 0.617021 (-8550 675);
PAINT SKYBLUE (-8550 675);
FORCEPROP 1 LAST VALUE 10UF
J 0
(-8550 925);
DISPLAY 0.617021 (-8550 925);
PAINT SKYBLUE (-8550 925);
FORCEPROP 1 LAST LOCATION C4L2
J 0
(-8550 975);
DISPLAY 0.617021 (-8550 975);
PAINT AQUA (-8550 975);
FORCEPROP 1 LAST PART_NUMBER E15431-001
J 0
(-8550 725);
DISPLAY 0.617021 (-8550 725);
PAINT BLUE (-8550 725);
FORCEPROP 0 LAST GROUP PWR_MLCC_CAP
J 0
(-8544 637);
DISPLAY 0.638298 (-8544 637);
PAINT BROWN (-8544 637);
DISPLAY BOTH (-8544 637);
FORCEPROP 2 LAST CDS_LIB mstr_discrete
J 0
(-8600 875);
PAINT ORANGE (-8600 875);
DISPLAY INVISIBLE (-8600 875);
FORCEPROP 2 LAST CDS_LOCATION C4L2
J 0
(-8550 975);
DISPLAY 0.617021 (-8550 975);
PAINT AQUA (-8550 975);
DISPLAY INVISIBLE (-8550 975);
FORCEPROP 2 LAST ROOM PVPP_KLM_VR
J 0
(-8550 1025);
PAINT MONO (-8550 1025);
DISPLAY INVISIBLE (-8550 1025);
FORCEPROP 1 LAST PATH I102
J 0
(-8550 1025);
DISPLAY 0.978723 (-8550 1025);
PAINT WHITE (-8550 1025);
DISPLAY INVISIBLE (-8550 1025);
FORCEPROP 2 LAST $SEC 1
J 0
(-8550 1075);
PAINT MONO (-8550 1075);
DISPLAY INVISIBLE (-8550 1075);
FORCEPROP 2 LAST CDS_SEC 1
J 0
(-8550 1075);
PAINT MONO (-8550 1075);
DISPLAY INVISIBLE (-8550 1075);
FORCEPROP 2 LAST BOM_COST MEM_VRD_PVPP_AB
J 0
(-8550 1025);
PAINT MONO (-8550 1025);
DISPLAY INVISIBLE (-8550 1025);
FORCEADD PVPP_DEF..1
(-8600 1150);
FORCEPROP 3 LASTPIN (-8600 1100) SIG_NAME PVPP_DEF\g
J 0
(-8590 1110);
DISPLAY 0.659574 (-8590 1110);
PAINT MONO (-8590 1110);
DISPLAY INVISIBLE (-8590 1110);
FORCEPROP 1 LAST VOLTAGE 2.5V
J 0
(-8645 1107);
DISPLAY 0.340426 (-8645 1107);
PAINT SKYBLUE (-8645 1107);
DISPLAY INVISIBLE (-8645 1107);
FORCEPROP 2 LAST CDS_LIB mstr_symbols
J 0
(-8600 1150);
PAINT ORANGE (-8600 1150);
DISPLAY INVISIBLE (-8600 1150);
FORCEPROP 1 LAST PATH I103
J 0
(-8550 1175);
DISPLAY 0.872340 (-8550 1175);
PAINT AQUA (-8550 1175);
DISPLAY INVISIBLE (-8550 1175);
FORCEPROP 2 LAST BOM_COST MEM_VRD_PVPP_AB
J 0
(-8525 1250);
PAINT MONO (-8525 1250);
DISPLAY INVISIBLE (-8525 1250);
FORCEPROP 2 LAST ROOM PVPP_KLM_VR
J 0
(-8350 1250);
PAINT ORANGE (-8350 1250);
DISPLAY INVISIBLE (-8350 1250);
FORCEPROP 1 LAST BODY_TYPE PLUMBING
J 0
(-8645 1107);
DISPLAY 0.340426 (-8645 1107);
PAINT GREEN (-8645 1107);
DISPLAY INVISIBLE (-8645 1107);
FORCEPROP 1 LAST HDL_POWER PVPP_DEF
J 1
(-8600 1200);
DISPLAY 0.872340 (-8600 1200);
PAINT GREEN (-8600 1200);
DISPLAY INVISIBLE (-8600 1200);
FORCEADD CAP..1
(-8325 875);
FORCEPROP 1 LASTPIN (-8325 775) $PN 2
J 0
(-8315 755);
DISPLAY 0.617021 (-8315 755);
PAINT GREEN (-8315 755);
FORCEPROP 1 LASTPIN (-8325 975) $PN 1
J 0
(-8315 955);
DISPLAY 0.617021 (-8315 955);
PAINT GREEN (-8315 955);
FORCEPROP 1 LAST VALUE 10UF
J 0
(-8275 925);
DISPLAY 0.617021 (-8275 925);
PAINT SKYBLUE (-8275 925);
FORCEPROP 1 LAST LOCATION C6A3
J 0
(-8275 975);
DISPLAY 0.617021 (-8275 975);
PAINT AQUA (-8275 975);
FORCEPROP 1 LAST VOLTAGE 4V
J 0
(-8275 875);
DISPLAY 0.638298 (-8275 875);
PAINT SKYBLUE (-8275 875);
FORCEPROP 1 LAST TOLERANCE 20%
J 0
(-8275 825);
DISPLAY 0.617021 (-8275 825);
PAINT SKYBLUE (-8275 825);
FORCEPROP 1 LAST MATERIAL X6S
J 0
(-8275 775);
DISPLAY 0.617021 (-8275 775);
PAINT SKYBLUE (-8275 775);
FORCEPROP 1 LAST PART_NUMBER E15431-001
J 0
(-8275 725);
DISPLAY 0.617021 (-8275 725);
PAINT BLUE (-8275 725);
FORCEPROP 1 LAST PACK_TYPE 0603LF
J 0
(-8275 675);
DISPLAY 0.617021 (-8275 675);
PAINT SKYBLUE (-8275 675);
FORCEPROP 0 LAST GROUP PWR_MLCC_CAP
J 0
(-8269 587);
DISPLAY 0.638298 (-8269 587);
PAINT BROWN (-8269 587);
DISPLAY BOTH (-8269 587);
FORCEPROP 2 LAST CDS_LIB mstr_discrete
J 0
(-8325 875);
PAINT ORANGE (-8325 875);
DISPLAY INVISIBLE (-8325 875);
FORCEPROP 2 LAST CDS_LOCATION C6A3
J 0
(-8275 975);
DISPLAY 0.617021 (-8275 975);
PAINT AQUA (-8275 975);
DISPLAY INVISIBLE (-8275 975);
FORCEPROP 2 LAST BOM_COST MEM_VRD_PVPP_AB
J 0
(-8275 1025);
PAINT MONO (-8275 1025);
DISPLAY INVISIBLE (-8275 1025);
FORCEPROP 2 LAST CDS_SEC 1
J 0
(-8275 1075);
PAINT MONO (-8275 1075);
DISPLAY INVISIBLE (-8275 1075);
FORCEPROP 2 LAST $SEC 1
J 0
(-8275 1075);
PAINT MONO (-8275 1075);
DISPLAY INVISIBLE (-8275 1075);
FORCEPROP 1 LAST PATH I104
J 0
(-8275 1025);
DISPLAY 0.978723 (-8275 1025);
PAINT WHITE (-8275 1025);
DISPLAY INVISIBLE (-8275 1025);
FORCEPROP 2 LAST ROOM PVPP_KLM_VR
J 0
(-8275 1025);
PAINT MONO (-8275 1025);
DISPLAY INVISIBLE (-8275 1025);
FORCEADD CAP..1
(-8050 875);
FORCEPROP 1 LAST VALUE 10UF
J 0
(-8000 925);
DISPLAY 0.617021 (-8000 925);
PAINT SKYBLUE (-8000 925);
FORCEPROP 1 LAST VOLTAGE 4V
J 0
(-8000 875);
DISPLAY 0.638298 (-8000 875);
PAINT SKYBLUE (-8000 875);
FORCEPROP 1 LAST MATERIAL X6S
J 0
(-8000 775);
DISPLAY 0.617021 (-8000 775);
PAINT SKYBLUE (-8000 775);
FORCEPROP 1 LASTPIN (-8050 975) $PN 1
J 0
(-8040 955);
DISPLAY 0.617021 (-8040 955);
PAINT GREEN (-8040 955);
FORCEPROP 1 LAST LOCATION C6A2
J 0
(-8000 975);
DISPLAY 0.617021 (-8000 975);
PAINT AQUA (-8000 975);
FORCEPROP 1 LASTPIN (-8050 775) $PN 2
J 0
(-8040 755);
DISPLAY 0.617021 (-8040 755);
PAINT GREEN (-8040 755);
FORCEPROP 1 LAST TOLERANCE 20%
J 0
(-8000 825);
DISPLAY 0.617021 (-8000 825);
PAINT SKYBLUE (-8000 825);
FORCEPROP 1 LAST PACK_TYPE 0603LF
J 0
(-8000 675);
DISPLAY 0.617021 (-8000 675);
PAINT SKYBLUE (-8000 675);
FORCEPROP 1 LAST PART_NUMBER E15431-001
J 0
(-8000 725);
DISPLAY 0.617021 (-8000 725);
PAINT BLUE (-8000 725);
FORCEPROP 0 LAST GROUP PWR_MLCC_CAP
J 0
(-7994 637);
DISPLAY 0.638298 (-7994 637);
PAINT BROWN (-7994 637);
DISPLAY BOTH (-7994 637);
FORCEPROP 2 LAST CDS_LIB mstr_discrete
J 0
(-8050 875);
PAINT ORANGE (-8050 875);
DISPLAY INVISIBLE (-8050 875);
FORCEPROP 2 LAST CDS_LOCATION C6A2
J 0
(-8000 975);
DISPLAY 0.617021 (-8000 975);
PAINT AQUA (-8000 975);
DISPLAY INVISIBLE (-8000 975);
FORCEPROP 2 LAST BOM_COST MEM_VRD_PVPP_AB
J 0
(-8000 1025);
PAINT MONO (-8000 1025);
DISPLAY INVISIBLE (-8000 1025);
FORCEPROP 2 LAST CDS_SEC 1
J 0
(-8000 1075);
PAINT MONO (-8000 1075);
DISPLAY INVISIBLE (-8000 1075);
FORCEPROP 2 LAST $SEC 1
J 0
(-8000 1075);
PAINT MONO (-8000 1075);
DISPLAY INVISIBLE (-8000 1075);
FORCEPROP 1 LAST PATH I105
J 0
(-8000 1025);
DISPLAY 0.978723 (-8000 1025);
PAINT WHITE (-8000 1025);
DISPLAY INVISIBLE (-8000 1025);
FORCEPROP 2 LAST ROOM PVPP_KLM_VR
J 0
(-8000 1025);
PAINT MONO (-8000 1025);
DISPLAY INVISIBLE (-8000 1025);
FORCEADD CAP..1
(-7775 875);
FORCEPROP 1 LASTPIN (-7775 975) $PN 1
J 0
(-7765 955);
DISPLAY 0.617021 (-7765 955);
PAINT GREEN (-7765 955);
FORCEPROP 1 LAST MATERIAL X6S
J 0
(-7725 775);
DISPLAY 0.617021 (-7725 775);
PAINT SKYBLUE (-7725 775);
FORCEPROP 1 LAST TOLERANCE 20%
J 0
(-7725 825);
DISPLAY 0.617021 (-7725 825);
PAINT SKYBLUE (-7725 825);
FORCEPROP 1 LAST LOCATION C4L3
J 0
(-7725 975);
DISPLAY 0.617021 (-7725 975);
PAINT AQUA (-7725 975);
FORCEPROP 1 LAST VALUE 10UF
J 0
(-7725 925);
DISPLAY 0.617021 (-7725 925);
PAINT SKYBLUE (-7725 925);
FORCEPROP 1 LAST VOLTAGE 4V
J 0
(-7725 875);
DISPLAY 0.638298 (-7725 875);
PAINT SKYBLUE (-7725 875);
FORCEPROP 1 LASTPIN (-7775 775) $PN 2
J 0
(-7765 755);
DISPLAY 0.617021 (-7765 755);
PAINT GREEN (-7765 755);
FORCEPROP 1 LAST PACK_TYPE 0603LF
J 0
(-7725 675);
DISPLAY 0.617021 (-7725 675);
PAINT SKYBLUE (-7725 675);
FORCEPROP 1 LAST PART_NUMBER E15431-001
J 0
(-7725 725);
DISPLAY 0.617021 (-7725 725);
PAINT BLUE (-7725 725);
FORCEPROP 0 LAST GROUP PWR_MLCC_CAP
J 0
(-7719 587);
DISPLAY 0.638298 (-7719 587);
PAINT BROWN (-7719 587);
DISPLAY BOTH (-7719 587);
FORCEPROP 2 LAST CDS_LIB mstr_discrete
J 0
(-7775 875);
PAINT ORANGE (-7775 875);
DISPLAY INVISIBLE (-7775 875);
FORCEPROP 2 LAST CDS_LOCATION C4L3
J 0
(-7725 975);
DISPLAY 0.617021 (-7725 975);
PAINT AQUA (-7725 975);
DISPLAY INVISIBLE (-7725 975);
FORCEPROP 2 LAST ROOM PVPP_KLM_VR
J 0
(-7725 1025);
PAINT MONO (-7725 1025);
DISPLAY INVISIBLE (-7725 1025);
FORCEPROP 1 LAST PATH I106
J 0
(-7725 1025);
DISPLAY 0.978723 (-7725 1025);
PAINT WHITE (-7725 1025);
DISPLAY INVISIBLE (-7725 1025);
FORCEPROP 2 LAST BOM_COST MEM_VRD_PVPP_AB
J 0
(-7725 1025);
PAINT MONO (-7725 1025);
DISPLAY INVISIBLE (-7725 1025);
FORCEPROP 2 LAST CDS_SEC 1
J 0
(-7725 1075);
PAINT MONO (-7725 1075);
DISPLAY INVISIBLE (-7725 1075);
FORCEPROP 2 LAST $SEC 1
J 0
(-7725 1075);
PAINT MONO (-7725 1075);
DISPLAY INVISIBLE (-7725 1075);
FORCEADD CAP..1
(-7500 875);
FORCEPROP 1 LAST MATERIAL X6S
J 0
(-7450 775);
DISPLAY 0.617021 (-7450 775);
PAINT SKYBLUE (-7450 775);
FORCEPROP 1 LAST VALUE 10UF
J 0
(-7450 925);
DISPLAY 0.617021 (-7450 925);
PAINT SKYBLUE (-7450 925);
FORCEPROP 1 LASTPIN (-7500 975) $PN 1
J 0
(-7490 955);
DISPLAY 0.617021 (-7490 955);
PAINT GREEN (-7490 955);
FORCEPROP 1 LASTPIN (-7500 775) $PN 2
J 0
(-7490 755);
DISPLAY 0.617021 (-7490 755);
PAINT GREEN (-7490 755);
FORCEPROP 1 LAST PART_NUMBER E15431-001
J 0
(-7450 725);
DISPLAY 0.617021 (-7450 725);
PAINT BLUE (-7450 725);
FORCEPROP 1 LAST LOCATION C4L4
J 0
(-7450 975);
DISPLAY 0.617021 (-7450 975);
PAINT AQUA (-7450 975);
FORCEPROP 1 LAST PACK_TYPE 0603LF
J 0
(-7450 675);
DISPLAY 0.617021 (-7450 675);
PAINT SKYBLUE (-7450 675);
FORCEPROP 1 LAST TOLERANCE 20%
J 0
(-7450 825);
DISPLAY 0.617021 (-7450 825);
PAINT SKYBLUE (-7450 825);
FORCEPROP 1 LAST VOLTAGE 4V
J 0
(-7450 875);
DISPLAY 0.638298 (-7450 875);
PAINT SKYBLUE (-7450 875);
FORCEPROP 0 LAST GROUP PWR_MLCC_CAP
J 0
(-7444 637);
DISPLAY 0.638298 (-7444 637);
PAINT BROWN (-7444 637);
DISPLAY BOTH (-7444 637);
FORCEPROP 2 LAST ROOM PVPP_KLM_VR
J 0
(-7450 1025);
PAINT MONO (-7450 1025);
DISPLAY INVISIBLE (-7450 1025);
FORCEPROP 1 LAST PATH I108
J 0
(-7450 1025);
DISPLAY 0.978723 (-7450 1025);
PAINT WHITE (-7450 1025);
DISPLAY INVISIBLE (-7450 1025);
FORCEPROP 2 LAST $SEC 1
J 0
(-7450 1075);
PAINT MONO (-7450 1075);
DISPLAY INVISIBLE (-7450 1075);
FORCEPROP 2 LAST CDS_SEC 1
J 0
(-7450 1075);
PAINT MONO (-7450 1075);
DISPLAY INVISIBLE (-7450 1075);
FORCEPROP 2 LAST BOM_COST MEM_VRD_PVPP_AB
J 0
(-7450 1025);
PAINT MONO (-7450 1025);
DISPLAY INVISIBLE (-7450 1025);
FORCEPROP 2 LAST CDS_LOCATION C4L4
J 0
(-7450 975);
DISPLAY 0.617021 (-7450 975);
PAINT AQUA (-7450 975);
DISPLAY INVISIBLE (-7450 975);
FORCEPROP 2 LAST CDS_LIB mstr_discrete
J 0
(-7500 875);
PAINT ORANGE (-7500 875);
DISPLAY INVISIBLE (-7500 875);
FORCEADD CAP..1
(-7200 875);
FORCEPROP 1 LAST PART_NUMBER E15431-001
J 0
(-7150 725);
DISPLAY 0.617021 (-7150 725);
PAINT BLUE (-7150 725);
FORCEPROP 1 LAST TOLERANCE 20%
J 0
(-7150 825);
DISPLAY 0.617021 (-7150 825);
PAINT SKYBLUE (-7150 825);
FORCEPROP 1 LAST MATERIAL X6S
J 0
(-7150 775);
DISPLAY 0.617021 (-7150 775);
PAINT SKYBLUE (-7150 775);
FORCEPROP 1 LASTPIN (-7200 775) $PN 2
J 0
(-7190 755);
DISPLAY 0.617021 (-7190 755);
PAINT GREEN (-7190 755);
FORCEPROP 1 LAST VALUE 10UF
J 0
(-7150 925);
DISPLAY 0.617021 (-7150 925);
PAINT SKYBLUE (-7150 925);
FORCEPROP 1 LAST LOCATION C6A7
J 0
(-7150 975);
DISPLAY 0.617021 (-7150 975);
PAINT AQUA (-7150 975);
FORCEPROP 1 LASTPIN (-7200 975) $PN 1
J 0
(-7190 955);
DISPLAY 0.617021 (-7190 955);
PAINT GREEN (-7190 955);
FORCEPROP 1 LAST VOLTAGE 4V
J 0
(-7150 875);
DISPLAY 0.638298 (-7150 875);
PAINT SKYBLUE (-7150 875);
FORCEPROP 1 LAST PACK_TYPE 0603LF
J 0
(-7150 675);
DISPLAY 0.617021 (-7150 675);
PAINT SKYBLUE (-7150 675);
FORCEPROP 0 LAST GROUP PWR_MLCC_CAP
J 0
(-7144 587);
DISPLAY 0.638298 (-7144 587);
PAINT BROWN (-7144 587);
DISPLAY BOTH (-7144 587);
FORCEPROP 2 LAST BOM_COST MEM_VRD_PVPP_AB
J 0
(-7150 1025);
PAINT MONO (-7150 1025);
DISPLAY INVISIBLE (-7150 1025);
FORCEPROP 2 LAST CDS_SEC 1
J 0
(-7150 1075);
PAINT MONO (-7150 1075);
DISPLAY INVISIBLE (-7150 1075);
FORCEPROP 2 LAST $SEC 1
J 0
(-7150 1075);
PAINT MONO (-7150 1075);
DISPLAY INVISIBLE (-7150 1075);
FORCEPROP 1 LAST PATH I109
J 0
(-7150 1025);
DISPLAY 0.978723 (-7150 1025);
PAINT WHITE (-7150 1025);
DISPLAY INVISIBLE (-7150 1025);
FORCEPROP 2 LAST ROOM PVPP_KLM_VR
J 0
(-7150 1025);
PAINT MONO (-7150 1025);
DISPLAY INVISIBLE (-7150 1025);
FORCEPROP 2 LAST CDS_LOCATION C6A7
J 0
(-7150 975);
DISPLAY 0.617021 (-7150 975);
PAINT AQUA (-7150 975);
DISPLAY INVISIBLE (-7150 975);
FORCEPROP 2 LAST CDS_LIB mstr_discrete
J 0
(-7200 875);
PAINT ORANGE (-7200 875);
DISPLAY INVISIBLE (-7200 875);
FORCEADD CAP..1
(-6925 875);
FORCEPROP 1 LAST VOLTAGE 4V
J 0
(-6875 875);
DISPLAY 0.638298 (-6875 875);
PAINT SKYBLUE (-6875 875);
FORCEPROP 1 LAST LOCATION C6A6
J 0
(-6875 975);
DISPLAY 0.617021 (-6875 975);
PAINT AQUA (-6875 975);
FORCEPROP 1 LAST MATERIAL X6S
J 0
(-6875 775);
DISPLAY 0.617021 (-6875 775);
PAINT SKYBLUE (-6875 775);
FORCEPROP 1 LAST TOLERANCE 20%
J 0
(-6875 825);
DISPLAY 0.617021 (-6875 825);
PAINT SKYBLUE (-6875 825);
FORCEPROP 1 LASTPIN (-6925 775) $PN 2
J 0
(-6915 755);
DISPLAY 0.617021 (-6915 755);
PAINT GREEN (-6915 755);
FORCEPROP 1 LASTPIN (-6925 975) $PN 1
J 0
(-6915 955);
DISPLAY 0.617021 (-6915 955);
PAINT GREEN (-6915 955);
FORCEPROP 1 LAST VALUE 10UF
J 0
(-6875 925);
DISPLAY 0.617021 (-6875 925);
PAINT SKYBLUE (-6875 925);
FORCEPROP 1 LAST PART_NUMBER E15431-001
J 0
(-6875 725);
DISPLAY 0.617021 (-6875 725);
PAINT BLUE (-6875 725);
FORCEPROP 1 LAST PACK_TYPE 0603LF
J 0
(-6875 675);
DISPLAY 0.617021 (-6875 675);
PAINT SKYBLUE (-6875 675);
FORCEPROP 0 LAST GROUP PWR_MLCC_CAP
J 0
(-6869 637);
DISPLAY 0.638298 (-6869 637);
PAINT BROWN (-6869 637);
DISPLAY BOTH (-6869 637);
FORCEPROP 2 LAST BOM_COST MEM_VRD_PVPP_AB
J 0
(-6875 1025);
PAINT MONO (-6875 1025);
DISPLAY INVISIBLE (-6875 1025);
FORCEPROP 2 LAST CDS_SEC 1
J 0
(-6875 1075);
PAINT MONO (-6875 1075);
DISPLAY INVISIBLE (-6875 1075);
FORCEPROP 2 LAST $SEC 1
J 0
(-6875 1075);
PAINT MONO (-6875 1075);
DISPLAY INVISIBLE (-6875 1075);
FORCEPROP 1 LAST PATH I110
J 0
(-6875 1025);
DISPLAY 0.978723 (-6875 1025);
PAINT WHITE (-6875 1025);
DISPLAY INVISIBLE (-6875 1025);
FORCEPROP 2 LAST ROOM PVPP_KLM_VR
J 0
(-6875 1025);
PAINT MONO (-6875 1025);
DISPLAY INVISIBLE (-6875 1025);
FORCEPROP 2 LAST CDS_LOCATION C6A6
J 0
(-6875 975);
DISPLAY 0.617021 (-6875 975);
PAINT AQUA (-6875 975);
DISPLAY INVISIBLE (-6875 975);
FORCEPROP 2 LAST CDS_LIB mstr_discrete
J 0
(-6925 875);
PAINT MONO (-6925 875);
DISPLAY INVISIBLE (-6925 875);
FORCEADD CAP..1
(-6625 875);
FORCEPROP 1 LAST VOLTAGE 4V
J 0
(-6575 875);
DISPLAY 0.638298 (-6575 875);
PAINT SKYBLUE (-6575 875);
FORCEPROP 1 LAST TOLERANCE 20%
J 0
(-6575 825);
DISPLAY 0.617021 (-6575 825);
PAINT SKYBLUE (-6575 825);
FORCEPROP 1 LAST VALUE 10UF
J 0
(-6575 925);
DISPLAY 0.617021 (-6575 925);
PAINT SKYBLUE (-6575 925);
FORCEPROP 1 LAST LOCATION C4M3
J 0
(-6575 975);
DISPLAY 0.617021 (-6575 975);
PAINT AQUA (-6575 975);
FORCEPROP 1 LAST PART_NUMBER E15431-001
J 0
(-6575 725);
DISPLAY 0.617021 (-6575 725);
PAINT BLUE (-6575 725);
FORCEPROP 1 LASTPIN (-6625 975) $PN 1
J 0
(-6615 955);
DISPLAY 0.617021 (-6615 955);
PAINT GREEN (-6615 955);
FORCEPROP 1 LAST MATERIAL X6S
J 0
(-6575 775);
DISPLAY 0.617021 (-6575 775);
PAINT SKYBLUE (-6575 775);
FORCEPROP 1 LASTPIN (-6625 775) $PN 2
J 0
(-6615 755);
DISPLAY 0.617021 (-6615 755);
PAINT GREEN (-6615 755);
FORCEPROP 1 LAST PACK_TYPE 0603LF
J 0
(-6575 675);
DISPLAY 0.617021 (-6575 675);
PAINT SKYBLUE (-6575 675);
FORCEPROP 0 LAST GROUP PWR_MLCC_CAP
J 0
(-6569 587);
DISPLAY 0.638298 (-6569 587);
PAINT BROWN (-6569 587);
DISPLAY BOTH (-6569 587);
FORCEPROP 2 LAST ROOM PVPP_KLM_VR
J 0
(-6575 1025);
PAINT MONO (-6575 1025);
DISPLAY INVISIBLE (-6575 1025);
FORCEPROP 1 LAST PATH I111
J 0
(-6575 1025);
DISPLAY 0.978723 (-6575 1025);
PAINT WHITE (-6575 1025);
DISPLAY INVISIBLE (-6575 1025);
FORCEPROP 2 LAST $SEC 1
J 0
(-6575 1075);
PAINT MONO (-6575 1075);
DISPLAY INVISIBLE (-6575 1075);
FORCEPROP 2 LAST CDS_SEC 1
J 0
(-6575 1075);
PAINT MONO (-6575 1075);
DISPLAY INVISIBLE (-6575 1075);
FORCEPROP 2 LAST BOM_COST MEM_VRD_PVPP_AB
J 0
(-6575 1025);
PAINT MONO (-6575 1025);
DISPLAY INVISIBLE (-6575 1025);
FORCEPROP 2 LAST CDS_LOCATION C4M3
J 0
(-6575 975);
DISPLAY 0.617021 (-6575 975);
PAINT AQUA (-6575 975);
DISPLAY INVISIBLE (-6575 975);
FORCEPROP 2 LAST CDS_LIB mstr_discrete
J 0
(-6625 875);
PAINT MONO (-6625 875);
DISPLAY INVISIBLE (-6625 875);
FORCEADD CAP..1
(-6325 875);
FORCEPROP 1 LAST VOLTAGE 4V
J 0
(-6275 875);
DISPLAY 0.638298 (-6275 875);
PAINT SKYBLUE (-6275 875);
FORCEPROP 1 LAST MATERIAL X6S
J 0
(-6275 775);
DISPLAY 0.617021 (-6275 775);
PAINT SKYBLUE (-6275 775);
FORCEPROP 1 LASTPIN (-6325 775) $PN 2
J 0
(-6315 755);
DISPLAY 0.617021 (-6315 755);
PAINT GREEN (-6315 755);
FORCEPROP 1 LAST PACK_TYPE 0603LF
J 0
(-6275 675);
DISPLAY 0.617021 (-6275 675);
PAINT SKYBLUE (-6275 675);
FORCEPROP 1 LAST VALUE 10UF
J 0
(-6275 925);
DISPLAY 0.617021 (-6275 925);
PAINT SKYBLUE (-6275 925);
FORCEPROP 1 LAST TOLERANCE 20%
J 0
(-6275 825);
DISPLAY 0.617021 (-6275 825);
PAINT SKYBLUE (-6275 825);
FORCEPROP 1 LASTPIN (-6325 975) $PN 1
J 0
(-6315 955);
DISPLAY 0.617021 (-6315 955);
PAINT GREEN (-6315 955);
FORCEPROP 1 LAST LOCATION C4M4
J 0
(-6275 975);
DISPLAY 0.617021 (-6275 975);
PAINT AQUA (-6275 975);
FORCEPROP 1 LAST PART_NUMBER E15431-001
J 0
(-6275 725);
DISPLAY 0.617021 (-6275 725);
PAINT BLUE (-6275 725);
FORCEPROP 0 LAST GROUP PWR_MLCC_CAP
J 0
(-6269 637);
DISPLAY 0.638298 (-6269 637);
PAINT BROWN (-6269 637);
DISPLAY BOTH (-6269 637);
FORCEPROP 2 LAST ROOM PVPP_KLM_VR
J 0
(-6275 1025);
PAINT MONO (-6275 1025);
DISPLAY INVISIBLE (-6275 1025);
FORCEPROP 1 LAST PATH I125
J 0
(-6275 1025);
DISPLAY 0.978723 (-6275 1025);
PAINT WHITE (-6275 1025);
DISPLAY INVISIBLE (-6275 1025);
FORCEPROP 2 LAST $SEC 1
J 0
(-6275 1075);
PAINT MONO (-6275 1075);
DISPLAY INVISIBLE (-6275 1075);
FORCEPROP 2 LAST CDS_SEC 1
J 0
(-6275 1075);
PAINT MONO (-6275 1075);
DISPLAY INVISIBLE (-6275 1075);
FORCEPROP 2 LAST BOM_COST MEM_VRD_PVPP_AB
J 0
(-6275 1025);
PAINT MONO (-6275 1025);
DISPLAY INVISIBLE (-6275 1025);
FORCEPROP 2 LAST CDS_LIB mstr_discrete
J 0
(-6325 875);
PAINT MONO (-6325 875);
DISPLAY INVISIBLE (-6325 875);
FORCEPROP 2 LAST CDS_LOCATION C4M4
J 0
(-6275 975);
DISPLAY 0.617021 (-6275 975);
PAINT AQUA (-6275 975);
DISPLAY INVISIBLE (-6275 975);
FORCEADD CAP..1
(-6050 875);
FORCEPROP 1 LASTPIN (-6050 775) $PN 2
J 0
(-6040 755);
DISPLAY 0.617021 (-6040 755);
PAINT GREEN (-6040 755);
FORCEPROP 1 LASTPIN (-6050 975) $PN 1
J 0
(-6040 955);
DISPLAY 0.617021 (-6040 955);
PAINT GREEN (-6040 955);
FORCEPROP 1 LAST PACK_TYPE 0603LF
J 0
(-6000 675);
DISPLAY 0.617021 (-6000 675);
PAINT SKYBLUE (-6000 675);
FORCEPROP 1 LAST VALUE 10UF
J 0
(-6000 925);
DISPLAY 0.617021 (-6000 925);
PAINT SKYBLUE (-6000 925);
FORCEPROP 1 LAST LOCATION C6B2
J 0
(-6000 975);
DISPLAY 0.617021 (-6000 975);
PAINT AQUA (-6000 975);
FORCEPROP 1 LAST VOLTAGE 4V
J 0
(-6000 875);
DISPLAY 0.638298 (-6000 875);
PAINT SKYBLUE (-6000 875);
FORCEPROP 1 LAST PART_NUMBER E15431-001
J 0
(-6000 725);
DISPLAY 0.617021 (-6000 725);
PAINT BLUE (-6000 725);
FORCEPROP 1 LAST MATERIAL X6S
J 0
(-6000 775);
DISPLAY 0.617021 (-6000 775);
PAINT SKYBLUE (-6000 775);
FORCEPROP 1 LAST TOLERANCE 20%
J 0
(-6000 825);
DISPLAY 0.617021 (-6000 825);
PAINT SKYBLUE (-6000 825);
FORCEPROP 0 LAST GROUP PWR_MLCC_CAP
J 0
(-5994 587);
DISPLAY 0.638298 (-5994 587);
PAINT BROWN (-5994 587);
DISPLAY BOTH (-5994 587);
FORCEPROP 2 LAST CDS_LIB mstr_discrete
J 0
(-6050 875);
PAINT MONO (-6050 875);
DISPLAY INVISIBLE (-6050 875);
FORCEPROP 2 LAST CDS_LOCATION C6B2
J 0
(-6000 975);
DISPLAY 0.617021 (-6000 975);
PAINT AQUA (-6000 975);
DISPLAY INVISIBLE (-6000 975);
FORCEPROP 2 LAST ROOM PVPP_KLM_VR
J 0
(-6000 1025);
PAINT MONO (-6000 1025);
DISPLAY INVISIBLE (-6000 1025);
FORCEPROP 1 LAST PATH I126
J 0
(-6000 1025);
DISPLAY 0.978723 (-6000 1025);
PAINT WHITE (-6000 1025);
DISPLAY INVISIBLE (-6000 1025);
FORCEPROP 2 LAST BOM_COST MEM_VRD_PVPP_AB
J 0
(-6000 1025);
PAINT MONO (-6000 1025);
DISPLAY INVISIBLE (-6000 1025);
FORCEPROP 2 LAST $SEC 1
J 0
(-6000 1075);
PAINT MONO (-6000 1075);
DISPLAY INVISIBLE (-6000 1075);
FORCEPROP 2 LAST CDS_SEC 1
J 0
(-6000 1075);
PAINT MONO (-6000 1075);
DISPLAY INVISIBLE (-6000 1075);
FORCEADD GND..1
(-8600 475);
FORCEPROP 3 LASTPIN (-8600 525) SIG_NAME GND\g
J 0
(-8590 535);
DISPLAY 0.659574 (-8590 535);
PAINT MONO (-8590 535);
DISPLAY INVISIBLE (-8590 535);
FORCEPROP 1 LAST PATH I127
J 0
(-8525 475);
DISPLAY 0.872340 (-8525 475);
PAINT AQUA (-8525 475);
DISPLAY INVISIBLE (-8525 475);
FORCEPROP 1 LAST VOLTAGE 0
J 0
(-8600 475);
PAINT SKYBLUE (-8600 475);
DISPLAY INVISIBLE (-8600 475);
FORCEPROP 2 LAST CDS_LIB mstr_symbols
J 0
(-8600 475);
PAINT MONO (-8600 475);
DISPLAY INVISIBLE (-8600 475);
FORCEPROP 1 LAST SIZE 1B
J 0
(-8525 425);
DISPLAY 0.893617 (-8525 425);
PAINT GREEN (-8525 425);
DISPLAY INVISIBLE (-8525 425);
FORCEPROP 2 LAST BOM_COST MEM_VRD_PVPP_AB
J 0
(-8925 550);
PAINT MONO (-8925 550);
DISPLAY INVISIBLE (-8925 550);
FORCEPROP 2 LAST ROOM PVPP_KLM_VR
J 0
(-9150 550);
PAINT ORANGE (-9150 550);
DISPLAY INVISIBLE (-9150 550);
FORCEPROP 1 LAST BODY_TYPE PLUMBING
J 0
(-8645 432);
DISPLAY 0.340426 (-8645 432);
PAINT GREEN (-8645 432);
DISPLAY INVISIBLE (-8645 432);
FORCEPROP 1 LAST HDL_POWER GND
J 0
(-8600 625);
DISPLAY 0.893617 (-8600 625);
PAINT GREEN (-8600 625);
DISPLAY INVISIBLE (-8600 625);
FORCEADD CAP..1
(-5775 875);
FORCEPROP 1 LASTPIN (-5775 775) $PN 2
J 0
(-5765 755);
DISPLAY 0.617021 (-5765 755);
PAINT GREEN (-5765 755);
FORCEPROP 1 LAST MATERIAL X6S
J 0
(-5725 775);
DISPLAY 0.617021 (-5725 775);
PAINT SKYBLUE (-5725 775);
FORCEPROP 1 LASTPIN (-5775 975) $PN 1
J 0
(-5765 955);
DISPLAY 0.617021 (-5765 955);
PAINT GREEN (-5765 955);
FORCEPROP 1 LAST PACK_TYPE 0603LF
J 0
(-5725 675);
DISPLAY 0.617021 (-5725 675);
PAINT SKYBLUE (-5725 675);
FORCEPROP 1 LAST LOCATION C6B1
J 0
(-5725 975);
DISPLAY 0.617021 (-5725 975);
PAINT AQUA (-5725 975);
FORCEPROP 1 LAST PART_NUMBER E15431-001
J 0
(-5725 725);
DISPLAY 0.617021 (-5725 725);
PAINT BLUE (-5725 725);
FORCEPROP 1 LAST VALUE 10UF
J 0
(-5725 925);
DISPLAY 0.617021 (-5725 925);
PAINT SKYBLUE (-5725 925);
FORCEPROP 1 LAST VOLTAGE 4V
J 0
(-5725 875);
DISPLAY 0.638298 (-5725 875);
PAINT SKYBLUE (-5725 875);
FORCEPROP 1 LAST TOLERANCE 20%
J 0
(-5725 825);
DISPLAY 0.617021 (-5725 825);
PAINT SKYBLUE (-5725 825);
FORCEPROP 0 LAST GROUP PWR_MLCC_CAP
J 0
(-5719 637);
DISPLAY 0.638298 (-5719 637);
PAINT BROWN (-5719 637);
DISPLAY BOTH (-5719 637);
FORCEPROP 2 LAST CDS_LIB mstr_discrete
J 0
(-5775 875);
PAINT MONO (-5775 875);
DISPLAY INVISIBLE (-5775 875);
FORCEPROP 2 LAST CDS_LOCATION C6B1
J 0
(-5725 975);
DISPLAY 0.617021 (-5725 975);
PAINT AQUA (-5725 975);
DISPLAY INVISIBLE (-5725 975);
FORCEPROP 2 LAST ROOM PVPP_KLM_VR
J 0
(-5725 1025);
PAINT MONO (-5725 1025);
DISPLAY INVISIBLE (-5725 1025);
FORCEPROP 1 LAST PATH I128
J 0
(-5725 1025);
DISPLAY 0.978723 (-5725 1025);
PAINT WHITE (-5725 1025);
DISPLAY INVISIBLE (-5725 1025);
FORCEPROP 2 LAST BOM_COST MEM_VRD_PVPP_AB
J 0
(-5725 1025);
PAINT MONO (-5725 1025);
DISPLAY INVISIBLE (-5725 1025);
FORCEPROP 2 LAST $SEC 1
J 0
(-5725 1075);
PAINT MONO (-5725 1075);
DISPLAY INVISIBLE (-5725 1075);
FORCEPROP 2 LAST CDS_SEC 1
J 0
(-5725 1075);
PAINT MONO (-5725 1075);
DISPLAY INVISIBLE (-5725 1075);
FORCEADD CAP..1
(-5500 875);
FORCEPROP 1 LAST VOLTAGE 4V
J 0
(-5450 875);
DISPLAY 0.638298 (-5450 875);
PAINT SKYBLUE (-5450 875);
FORCEPROP 1 LAST PACK_TYPE 0603LF
J 0
(-5450 675);
DISPLAY 0.617021 (-5450 675);
PAINT SKYBLUE (-5450 675);
FORCEPROP 1 LAST VALUE 10UF
J 0
(-5450 925);
DISPLAY 0.617021 (-5450 925);
PAINT SKYBLUE (-5450 925);
FORCEPROP 1 LASTPIN (-5500 975) $PN 1
J 0
(-5490 955);
DISPLAY 0.617021 (-5490 955);
PAINT GREEN (-5490 955);
FORCEPROP 1 LAST TOLERANCE 20%
J 0
(-5450 825);
DISPLAY 0.617021 (-5450 825);
PAINT SKYBLUE (-5450 825);
FORCEPROP 1 LAST PART_NUMBER E15431-001
J 0
(-5450 725);
DISPLAY 0.617021 (-5450 725);
PAINT BLUE (-5450 725);
FORCEPROP 1 LASTPIN (-5500 775) $PN 2
J 0
(-5490 755);
DISPLAY 0.617021 (-5490 755);
PAINT GREEN (-5490 755);
FORCEPROP 1 LAST MATERIAL X6S
J 0
(-5450 775);
DISPLAY 0.617021 (-5450 775);
PAINT SKYBLUE (-5450 775);
FORCEPROP 1 LAST LOCATION C4L1
J 0
(-5450 975);
DISPLAY 0.617021 (-5450 975);
PAINT AQUA (-5450 975);
FORCEPROP 0 LAST GROUP PWR_MLCC_CAP
J 0
(-5444 587);
DISPLAY 0.638298 (-5444 587);
PAINT BROWN (-5444 587);
DISPLAY BOTH (-5444 587);
FORCEPROP 2 LAST CDS_LOCATION C4L1
J 0
(-5450 975);
DISPLAY 0.617021 (-5450 975);
PAINT AQUA (-5450 975);
DISPLAY INVISIBLE (-5450 975);
FORCEPROP 2 LAST CDS_LIB mstr_discrete
J 0
(-5500 875);
PAINT MONO (-5500 875);
DISPLAY INVISIBLE (-5500 875);
FORCEPROP 2 LAST ROOM PVPP_KLM_VR
J 0
(-5450 1025);
PAINT MONO (-5450 1025);
DISPLAY INVISIBLE (-5450 1025);
FORCEPROP 1 LAST PATH I129
J 0
(-5450 1025);
DISPLAY 0.978723 (-5450 1025);
PAINT WHITE (-5450 1025);
DISPLAY INVISIBLE (-5450 1025);
FORCEPROP 2 LAST SEC 1
J 0
(-5430 1095);
DISPLAY 0.680851 (-5430 1095);
PAINT MONO (-5430 1095);
DISPLAY INVISIBLE (-5430 1095);
FORCEPROP 2 LAST SEC_TYPE 0603LF
J 0
(-5430 1095);
DISPLAY 1.021277 (-5430 1095);
PAINT ORANGE (-5430 1095);
DISPLAY INVISIBLE (-5430 1095);
FORCEPROP 2 LAST BOM_COST MEM_VRD_PVPP_AB
J 0
(-5450 1025);
PAINT MONO (-5450 1025);
DISPLAY INVISIBLE (-5450 1025);
FORCEADD GND..1
(-1875 675);
FORCEPROP 3 LASTPIN (-1875 725) SIG_NAME GND\g
J 0
(-1865 735);
DISPLAY 0.659574 (-1865 735);
PAINT MONO (-1865 735);
DISPLAY INVISIBLE (-1865 735);
FORCEPROP 1 LAST PATH I149
J 0
(-1800 675);
DISPLAY 0.872340 (-1800 675);
PAINT AQUA (-1800 675);
DISPLAY INVISIBLE (-1800 675);
FORCEPROP 1 LAST SIZE 1B
J 0
(-1800 625);
DISPLAY 0.872340 (-1800 625);
PAINT AQUA (-1800 625);
DISPLAY INVISIBLE (-1800 625);
FORCEPROP 2 LAST CDS_LIB mstr_symbols
J 0
(-1875 675);
PAINT MONO (-1875 675);
DISPLAY INVISIBLE (-1875 675);
FORCEPROP 1 LAST VOLTAGE 0
J 0
(-1875 675);
PAINT SKYBLUE (-1875 675);
DISPLAY INVISIBLE (-1875 675);
FORCEPROP 2 LAST ROOM PVPP_KLM_VR
J 0
(-2450 750);
DISPLAY 1.042553 (-2450 750);
PAINT GREEN (-2450 750);
DISPLAY INVISIBLE (-2450 750);
FORCEPROP 2 LAST BOM_COST PVPP_KLM_VR
J 0
(-2725 750);
DISPLAY 1.042553 (-2725 750);
PAINT WHITE (-2725 750);
DISPLAY INVISIBLE (-2725 750);
FORCEPROP 1 LAST BODY_TYPE PLUMBING
J 0
(-1920 632);
DISPLAY 0.340426 (-1920 632);
PAINT GREEN (-1920 632);
DISPLAY INVISIBLE (-1920 632);
FORCEPROP 1 LAST HDL_POWER GND
J 0
(-1875 825);
DISPLAY 0.872340 (-1875 825);
PAINT GREEN (-1875 825);
DISPLAY INVISIBLE (-1875 825);
FORCEADD RES..1
(-1575 775);
FORCEPROP 1 LAST PACK_TYPE 0402
J 0
(-1650 575);
DISPLAY 0.617021 (-1650 575);
PAINT SKYBLUE (-1650 575);
FORCEPROP 1 LAST MATERIAL CHIP
J 0
(-1575 625);
DISPLAY 0.617021 (-1575 625);
PAINT SKYBLUE (-1575 625);
FORCEPROP 1 LASTPIN (-1675 775) $PN 1
J 0
(-1663 787);
DISPLAY 0.617021 (-1663 787);
PAINT WHITE (-1663 787);
FORCEPROP 1 LAST WATTAGE 1/16W
J 2
(-1575 625);
DISPLAY 0.617021 (-1575 625);
PAINT SKYBLUE (-1575 625);
FORCEPROP 1 LAST VALUE 0.0
J 2
(-1600 675);
DISPLAY 0.617021 (-1600 675);
PAINT SKYBLUE (-1600 675);
FORCEPROP 1 LAST LOCATION R7B20
J 0
(-1625 825);
DISPLAY 0.617021 (-1625 825);
PAINT AQUA (-1625 825);
FORCEPROP 1 LASTPIN (-1475 775) $PN 2
J 0
(-1513 787);
DISPLAY 0.617021 (-1513 787);
PAINT WHITE (-1513 787);
FORCEPROP 1 LAST TOLERANCE 5%
J 0
(-1575 675);
DISPLAY 0.617021 (-1575 675);
PAINT SKYBLUE (-1575 675);
FORCEPROP 1 LAST PART_NUMBER G21497-005
J 0
(-1700 725);
DISPLAY 0.617021 (-1700 725);
PAINT BLUE (-1700 725);
FORCEPROP 2 LAST ROOM PVPP_KLM_VR
J 0
(-1625 850);
PAINT GREEN (-1625 850);
DISPLAY INVISIBLE (-1625 850);
FORCEPROP 1 LAST PATH I150
J 0
(-1625 925);
DISPLAY 0.978723 (-1625 925);
PAINT WHITE (-1625 925);
DISPLAY INVISIBLE (-1625 925);
FORCEPROP 2 LAST $SEC 1
J 0
(-1610 980);
PAINT MONO (-1610 980);
DISPLAY INVISIBLE (-1610 980);
FORCEPROP 2 LAST CDS_SEC 1
J 0
(-1615 960);
PAINT MONO (-1615 960);
DISPLAY INVISIBLE (-1615 960);
FORCEPROP 2 LAST CDS_LIB mstr_discrete
J 0
(-1575 775);
PAINT MONO (-1575 775);
DISPLAY INVISIBLE (-1575 775);
FORCEADD AGND_SCSI..1
(-1325 675);
FORCEPROP 3 LASTPIN (-1325 725) SIG_NAME AGND_PVPP_DEF\g
J 0
(-1315 735);
DISPLAY 0.659574 (-1315 735);
PAINT MONO (-1315 735);
DISPLAY INVISIBLE (-1315 735);
FORCEPROP 1 LAST HDL_POWER AGND_PVPP_DEF
J 1
(-1250 600);
DISPLAY 0.617021 (-1250 600);
PAINT GREEN (-1250 600);
FORCEPROP 1 LAST PATH I151
J 0
(-1250 675);
DISPLAY 0.872340 (-1250 675);
PAINT AQUA (-1250 675);
DISPLAY INVISIBLE (-1250 675);
FORCEPROP 2 LAST ROOM PVPP_KLM_VR
J 0
(-1475 625);
DISPLAY 1.042553 (-1475 625);
PAINT GREEN (-1475 625);
DISPLAY INVISIBLE (-1475 625);
FORCEPROP 2 LAST CDS_LIB mstr_symbols
J 0
(-1325 675);
PAINT ORANGE (-1325 675);
DISPLAY INVISIBLE (-1325 675);
FORCEPROP 2 LAST BOM_COST PVPP_KLM_VR
J 0
(-1475 625);
DISPLAY 1.042553 (-1475 625);
PAINT WHITE (-1475 625);
DISPLAY INVISIBLE (-1475 625);
FORCEPROP 1 LAST VOLTAGE 0.0V
J 0
(-1370 632);
DISPLAY 0.340426 (-1370 632);
PAINT SKYBLUE (-1370 632);
DISPLAY INVISIBLE (-1370 632);
FORCEPROP 1 LAST BODY_TYPE PLUMBING
J 0
(-1370 632);
DISPLAY 0.340426 (-1370 632);
PAINT GREEN (-1370 632);
DISPLAY INVISIBLE (-1370 632);
FORCEADD PVPP_DEF..1
(-1150 3975);
FORCEPROP 3 LASTPIN (-1150 3925) SIG_NAME PVPP_DEF\g
J 0
(-1140 3935);
DISPLAY 0.659574 (-1140 3935);
PAINT MONO (-1140 3935);
DISPLAY INVISIBLE (-1140 3935);
FORCEPROP 2 LAST BOM_COST PVPP_KLM_VR
J 0
(-1075 4075);
PAINT MONO (-1075 4075);
DISPLAY INVISIBLE (-1075 4075);
FORCEPROP 2 LAST ROOM PVPP_KLM_VR
J 0
(-900 4075);
PAINT ORANGE (-900 4075);
DISPLAY INVISIBLE (-900 4075);
FORCEPROP 1 LAST PATH I167
J 0
(-1100 4000);
DISPLAY 0.872340 (-1100 4000);
PAINT AQUA (-1100 4000);
DISPLAY INVISIBLE (-1100 4000);
FORCEPROP 2 LAST CDS_LIB mstr_symbols
J 0
(-1150 3975);
PAINT ORANGE (-1150 3975);
DISPLAY INVISIBLE (-1150 3975);
FORCEPROP 1 LAST VOLTAGE 2.5V
J 0
(-1195 3932);
DISPLAY 0.340426 (-1195 3932);
PAINT SKYBLUE (-1195 3932);
DISPLAY INVISIBLE (-1195 3932);
FORCEPROP 1 LAST BODY_TYPE PLUMBING
J 0
(-1195 3932);
DISPLAY 0.340426 (-1195 3932);
PAINT GREEN (-1195 3932);
DISPLAY INVISIBLE (-1195 3932);
FORCEPROP 1 LAST HDL_POWER PVPP_DEF
J 1
(-1150 4025);
DISPLAY 0.872340 (-1150 4025);
PAINT GREEN (-1150 4025);
DISPLAY INVISIBLE (-1150 4025);
FORCEADD OFFPAGE..1
(-7875 2825);
FORCEPROP 2 LAST $XR1 231 
J 0
(-8277 2825);
DISPLAY 0.638298 (-8277 2825);
PAINT MONO (-8277 2825);
FORCEPROP 2 LAST $XR0 191 
J 0
(-8157 2825);
DISPLAY 0.638298 (-8157 2825);
PAINT MONO (-8157 2825);
FORCEPROP 2 LAST CDS_LIB mstr_standard
J 0
(-7875 2825);
PAINT MONO (-7875 2825);
DISPLAY INVISIBLE (-7875 2825);
FORCEPROP 0 LAST TOLERANCE 1%
J 0
(-7825 2900);
PAINT SKYBLUE (-7825 2900);
DISPLAY INVISIBLE (-7825 2900);
FORCEPROP 2 LAST PATH I181
J 0
(-8125 2875);
DISPLAY 1.021277 (-8125 2875);
PAINT ORANGE (-8125 2875);
DISPLAY INVISIBLE (-8125 2875);
FORCEPROP 2 LAST ROOM PVPP_KLM_VR
J 0
(-8425 2900);
DISPLAY 1.042553 (-8425 2900);
PAINT GREEN (-8425 2900);
DISPLAY INVISIBLE (-8425 2900);
FORCEPROP 2 LAST BOM_COST PVPP_KLM_VR
J 0
(-8700 2900);
DISPLAY 1.042553 (-8700 2900);
PAINT WHITE (-8700 2900);
DISPLAY INVISIBLE (-8700 2900);
FORCEPROP 1 LAST OFFPAGE TRUE
J 0
(-7550 2700);
PAINT GREEN (-7550 2700);
DISPLAY INVISIBLE (-7550 2700);
FORCEPROP 1 LAST COMMENT_BODY TRUE
J 0
(-7750 2725);
DISPLAY 0.872340 (-7750 2725);
PAINT PEACH (-7750 2725);
DISPLAY INVISIBLE (-7750 2725);
FORCEADD CAP..1
R 2
(-6825 2500);
FORCEPROP 1 LAST PACK_TYPE 0402LF
J 2
(-6875 2300);
DISPLAY 0.617021 (-6875 2300);
PAINT SKYBLUE (-6875 2300);
FORCEPROP 1 LAST PART_NUMBER A36096-046
J 2
(-6850 2350);
DISPLAY 0.617021 (-6850 2350);
PAINT BLUE (-6850 2350);
FORCEPROP 1 LAST MATERIAL EMPTY
J 2
(-6875 2400);
DISPLAY 0.617021 (-6875 2400);
PAINT RED (-6875 2400);
FORCEPROP 1 LAST TOLERANCE 10%
J 2
(-6875 2450);
DISPLAY 0.617021 (-6875 2450);
PAINT SKYBLUE (-6875 2450);
FORCEPROP 1 LAST VOLTAGE 50V
J 2
(-6875 2500);
DISPLAY 0.617021 (-6875 2500);
PAINT SKYBLUE (-6875 2500);
FORCEPROP 1 LASTPIN (-6825 2600) $PN 1
J 2
(-6835 2580);
DISPLAY 0.617021 (-6835 2580);
PAINT WHITE (-6835 2580);
FORCEPROP 1 LAST LOCATION C7B9
J 2
(-6875 2600);
DISPLAY 0.617021 (-6875 2600);
PAINT AQUA (-6875 2600);
FORCEPROP 1 LAST VALUE 1000PF
J 2
(-6875 2550);
DISPLAY 0.617021 (-6875 2550);
PAINT SKYBLUE (-6875 2550);
FORCEPROP 1 LASTPIN (-6825 2400) $PN 2
J 2
(-6835 2380);
DISPLAY 0.617021 (-6835 2380);
PAINT WHITE (-6835 2380);
FORCEPROP 0 LAST FIN VR_1P2
J 2
(-6875 2800);
PAINT ORANGE (-6875 2800);
DISPLAY INVISIBLE (-6875 2800);
FORCEPROP 0 LAST REUSE_ID 1
J 2
(-6875 2700);
DISPLAY 1.042553 (-6875 2700);
PAINT ORANGE (-6875 2700);
DISPLAY INVISIBLE (-6875 2700);
FORCEPROP 2 LAST CDS_SEC 1
J 2
(-6875 2700);
DISPLAY 1.042553 (-6875 2700);
PAINT ORANGE (-6875 2700);
DISPLAY INVISIBLE (-6875 2700);
FORCEPROP 2 LAST $SEC 1
J 2
(-6875 2700);
DISPLAY 0.680851 (-6875 2700);
PAINT MONO (-6875 2700);
DISPLAY INVISIBLE (-6875 2700);
FORCEPROP 2 LAST CDS_LOCATION C7B9
J 2
(-6875 2600);
DISPLAY 0.617021 (-6875 2600);
PAINT AQUA (-6875 2600);
DISPLAY INVISIBLE (-6875 2600);
FORCEPROP 1 LAST PATH I185
J 2
(-6875 2650);
DISPLAY 0.978723 (-6875 2650);
PAINT WHITE (-6875 2650);
DISPLAY INVISIBLE (-6875 2650);
FORCEPROP 2 LAST CDS_LIB mstr_discrete
J 2
(-6825 2500);
PAINT MONO (-6825 2500);
DISPLAY INVISIBLE (-6825 2500);
FORCEPROP 2 LAST BOM_COST PVPP_KLM_VR
J 2
(-6825 2500);
PAINT WHITE (-6825 2500);
DISPLAY INVISIBLE (-6825 2500);
FORCEPROP 2 LAST ROOM PVPP_KLM_VR
J 2
(-6825 2500);
PAINT GREEN (-6825 2500);
DISPLAY INVISIBLE (-6825 2500);
FORCEADD CAP..1
(-5425 2175);
FORCEPROP 1 LAST TOLERANCE 10%
J 0
(-5350 2125);
DISPLAY 0.617021 (-5350 2125);
PAINT SKYBLUE (-5350 2125);
FORCEPROP 1 LAST VOLTAGE 16V
J 0
(-5350 2175);
DISPLAY 0.617021 (-5350 2175);
PAINT SKYBLUE (-5350 2175);
FORCEPROP 1 LAST LOCATION C7B11
J 0
(-5375 2275);
DISPLAY 0.617021 (-5375 2275);
PAINT AQUA (-5375 2275);
FORCEPROP 1 LAST VALUE 0.027UF
J 0
(-5375 2225);
DISPLAY 0.617021 (-5375 2225);
PAINT SKYBLUE (-5375 2225);
FORCEPROP 1 LASTPIN (-5425 2275) $PN 1
J 0
(-5415 2255);
DISPLAY 0.617021 (-5415 2255);
PAINT ORANGE (-5415 2255);
FORCEPROP 1 LASTPIN (-5425 2075) $PN 2
J 0
(-5415 2055);
DISPLAY 0.617021 (-5415 2055);
PAINT ORANGE (-5415 2055);
FORCEPROP 1 LAST PACK_TYPE 0402
J 0
(-5375 2075);
DISPLAY 0.617021 (-5375 2075);
PAINT SKYBLUE (-5375 2075);
FORCEPROP 1 LAST PART_NUMBER A36096-129
J 0
(-5400 2025);
DISPLAY 0.617021 (-5400 2025);
PAINT BLUE (-5400 2025);
FORCEPROP 1 LAST MATERIAL X7R
J 0
(-5375 1975);
DISPLAY 0.617021 (-5375 1975);
PAINT SKYBLUE (-5375 1975);
FORCEPROP 2 LAST SEC_TYPE 0402
J 0
(-5375 2375);
DISPLAY 1.021277 (-5375 2375);
PAINT ORANGE (-5375 2375);
DISPLAY INVISIBLE (-5375 2375);
FORCEPROP 2 LAST REUSE_ID 26
J 0
(-5375 2375);
DISPLAY 1.042553 (-5375 2375);
PAINT ORANGE (-5375 2375);
DISPLAY INVISIBLE (-5375 2375);
FORCEPROP 2 LAST BOM_COST PVPP_KLM_VR
J 0
(-5375 2325);
DISPLAY 1.042553 (-5375 2325);
PAINT WHITE (-5375 2325);
DISPLAY INVISIBLE (-5375 2325);
FORCEPROP 2 LAST SEC 1
J 0
(-5375 2375);
DISPLAY 0.680851 (-5375 2375);
PAINT MONO (-5375 2375);
DISPLAY INVISIBLE (-5375 2375);
FORCEPROP 2 LAST CDS_LOCATION C7B11
J 0
(-5375 2275);
DISPLAY 0.617021 (-5375 2275);
PAINT AQUA (-5375 2275);
DISPLAY INVISIBLE (-5375 2275);
FORCEPROP 1 LAST PATH I197
J 0
(-5375 2325);
DISPLAY 0.978723 (-5375 2325);
PAINT WHITE (-5375 2325);
DISPLAY INVISIBLE (-5375 2325);
FORCEPROP 2 LAST ROOM PVPP_KLM_VR
J 0
(-5375 2300);
PAINT GREEN (-5375 2300);
DISPLAY INVISIBLE (-5375 2300);
FORCEPROP 2 LAST CDS_LIB mstr_discrete
J 0
(-5425 2175);
PAINT MONO (-5425 2175);
DISPLAY INVISIBLE (-5425 2175);
FORCEADD GND..1
(-5425 3900);
FORCEPROP 3 LASTPIN (-5425 3950) SIG_NAME GND\g
J 0
(-5415 3960);
DISPLAY 0.659574 (-5415 3960);
PAINT MONO (-5415 3960);
DISPLAY INVISIBLE (-5415 3960);
FORCEPROP 1 LAST PATH I198
J 0
(-5350 3900);
DISPLAY 0.872340 (-5350 3900);
PAINT AQUA (-5350 3900);
DISPLAY INVISIBLE (-5350 3900);
FORCEPROP 2 LAST CDS_LIB mstr_symbols
J 0
(-5425 3900);
PAINT MONO (-5425 3900);
DISPLAY INVISIBLE (-5425 3900);
FORCEPROP 1 LAST VOLTAGE 0
J 0
(-5425 3900);
PAINT SKYBLUE (-5425 3900);
DISPLAY INVISIBLE (-5425 3900);
FORCEPROP 1 LAST SIZE 1B
J 0
(-5350 3850);
DISPLAY 0.872340 (-5350 3850);
PAINT GREEN (-5350 3850);
DISPLAY INVISIBLE (-5350 3850);
FORCEPROP 2 LAST ROOM PVPP_KLM_VR
J 0
(-6000 3975);
DISPLAY 1.042553 (-6000 3975);
PAINT GREEN (-6000 3975);
DISPLAY INVISIBLE (-6000 3975);
FORCEPROP 2 LAST BOM_COST PVPP_KLM_VR
J 0
(-6275 3975);
DISPLAY 1.042553 (-6275 3975);
PAINT WHITE (-6275 3975);
DISPLAY INVISIBLE (-6275 3975);
FORCEPROP 1 LAST BODY_TYPE PLUMBING
J 0
(-5470 3857);
DISPLAY 0.340426 (-5470 3857);
PAINT GREEN (-5470 3857);
DISPLAY INVISIBLE (-5470 3857);
FORCEPROP 1 LAST HDL_POWER GND
J 0
(-5425 4050);
DISPLAY 0.872340 (-5425 4050);
PAINT GREEN (-5425 4050);
DISPLAY INVISIBLE (-5425 4050);
FORCEADD P12V_STBY..1
(-8175 4500);
FORCEPROP 3 LASTPIN (-8175 4450) SIG_NAME P12V_STBY\g
J 0
(-8165 4460);
DISPLAY 0.659574 (-8165 4460);
PAINT MONO (-8165 4460);
DISPLAY INVISIBLE (-8165 4460);
FORCEPROP 1 LAST SIZE 1B
J 0
(-8130 4522);
DISPLAY 0.340426 (-8130 4522);
PAINT GREEN (-8130 4522);
DISPLAY INVISIBLE (-8130 4522);
FORCEPROP 1 LAST PATH I199
J 0
(-8130 4502);
DISPLAY 0.340426 (-8130 4502);
PAINT GREEN (-8130 4502);
DISPLAY INVISIBLE (-8130 4502);
FORCEPROP 1 LAST VOLTAGE 12.0V
J 0
(-8220 4457);
DISPLAY 0.340426 (-8220 4457);
PAINT SKYBLUE (-8220 4457);
DISPLAY INVISIBLE (-8220 4457);
FORCEPROP 2 LAST CDS_LIB mstr_symbols
J 0
(-8175 4500);
PAINT ORANGE (-8175 4500);
DISPLAY INVISIBLE (-8175 4500);
FORCEPROP 1 LAST BODY_TYPE PLUMBING
J 0
(-8220 4457);
DISPLAY 0.340426 (-8220 4457);
PAINT GREEN (-8220 4457);
DISPLAY INVISIBLE (-8220 4457);
FORCEPROP 1 LAST HDL_POWER P12V_STBY
J 0
(-8475 4375);
DISPLAY 0.872340 (-8475 4375);
PAINT ORANGE (-8475 4375);
DISPLAY INVISIBLE (-8475 4375);
FORCEADD FERRITE..1
(-7950 4300);
FORCEPROP 1 LAST PACK_TYPE SM
J 0
(-7870 4200);
DISPLAY 0.617021 (-7870 4200);
PAINT SKYBLUE (-7870 4200);
FORCEPROP 1 LASTPIN (-7850 4300) $PN 2
J 0
(-7870 4310);
DISPLAY 0.617021 (-7870 4310);
PAINT WHITE (-7870 4310);
FORCEPROP 1 LAST PART_NUMBER 656554-051
J 0
(-8045 4415);
DISPLAY 0.617021 (-8045 4415);
PAINT BLUE (-8045 4415);
FORCEPROP 1 LAST MATERIAL FB
J 0
(-7945 4200);
DISPLAY 0.617021 (-7945 4200);
PAINT SKYBLUE (-7945 4200);
FORCEPROP 1 LASTPIN (-8050 4300) $PN 1
J 2
(-8015 4310);
DISPLAY 0.617021 (-8015 4310);
PAINT WHITE (-8015 4310);
FORCEPROP 1 LAST VALUE 22
J 2
(-7970 4200);
DISPLAY 0.617021 (-7970 4200);
PAINT SKYBLUE (-7970 4200);
FORCEPROP 1 LAST LOCATION FB7B1
J 0
(-8045 4355);
DISPLAY 0.617021 (-8045 4355);
PAINT AQUA (-8045 4355);
FORCEPROP 2 LAST ROOM PVPP_KLM_VR
J 0
(-8025 4450);
DISPLAY 1.659574 (-8025 4450);
PAINT GREEN (-8025 4450);
DISPLAY INVISIBLE (-8025 4450);
FORCEPROP 1 LAST PATH I200
J 0
(-8045 4465);
DISPLAY 0.872340 (-8045 4465);
PAINT PURPLE (-8045 4465);
DISPLAY INVISIBLE (-8045 4465);
FORCEPROP 2 LAST CDS_LOCATION FB7B1
J 0
(-8045 4355);
DISPLAY 0.617021 (-8045 4355);
PAINT AQUA (-8045 4355);
DISPLAY INVISIBLE (-8045 4355);
FORCEPROP 2 LAST SEC 1
J 0
(-8025 4525);
DISPLAY 1.106383 (-8025 4525);
PAINT MONO (-8025 4525);
DISPLAY INVISIBLE (-8025 4525);
FORCEPROP 2 LAST SEC_TYPE SM
J 0
(-8025 4525);
DISPLAY 1.659574 (-8025 4525);
PAINT ORANGE (-8025 4525);
DISPLAY INVISIBLE (-8025 4525);
FORCEPROP 0 LAST TOLERANCE 1%
J 0
(-8025 4450);
PAINT SKYBLUE (-8025 4450);
DISPLAY INVISIBLE (-8025 4450);
FORCEPROP 2 LAST CDS_LIB mstr_discrete
J 0
(-7950 4300);
PAINT MONO (-7950 4300);
DISPLAY INVISIBLE (-7950 4300);
FORCEADD CAP..1
(-5425 4150);
FORCEPROP 1 LAST PACK_TYPE 0402
J 0
(-5375 3950);
DISPLAY 0.617021 (-5375 3950);
PAINT SKYBLUE (-5375 3950);
FORCEPROP 1 LAST PART_NUMBER D97712-011
J 0
(-5375 4000);
DISPLAY 0.617021 (-5375 4000);
PAINT BLUE (-5375 4000);
FORCEPROP 1 LASTPIN (-5425 4050) $PN 2
J 0
(-5415 4030);
DISPLAY 0.617021 (-5415 4030);
PAINT WHITE (-5415 4030);
FORCEPROP 1 LAST MATERIAL X6S
J 0
(-5375 4050);
DISPLAY 0.617021 (-5375 4050);
PAINT SKYBLUE (-5375 4050);
FORCEPROP 1 LASTPIN (-5425 4250) $PN 1
J 0
(-5415 4230);
DISPLAY 0.617021 (-5415 4230);
PAINT WHITE (-5415 4230);
FORCEPROP 1 LAST LOCATION C3M9
J 0
(-5375 4250);
DISPLAY 0.617021 (-5375 4250);
PAINT AQUA (-5375 4250);
FORCEPROP 1 LAST VOLTAGE 16V
J 0
(-5375 4150);
DISPLAY 0.617021 (-5375 4150);
PAINT SKYBLUE (-5375 4150);
FORCEPROP 1 LAST TOLERANCE 10%
J 0
(-5375 4100);
DISPLAY 0.617021 (-5375 4100);
PAINT SKYBLUE (-5375 4100);
FORCEPROP 1 LAST VALUE 1.0UF
J 0
(-5375 4200);
DISPLAY 0.617021 (-5375 4200);
PAINT SKYBLUE (-5375 4200);
FORCEPROP 2 LAST ROOM PVPP_KLM_VR
J 0
(-5425 4150);
PAINT GREEN (-5425 4150);
DISPLAY INVISIBLE (-5425 4150);
FORCEPROP 2 LAST CDS_LIB mstr_discrete
J 0
(-5425 4150);
PAINT MONO (-5425 4150);
DISPLAY INVISIBLE (-5425 4150);
FORCEPROP 2 LAST BOM_COST PVPP_KLM_VR
J 0
(-5425 4150);
PAINT WHITE (-5425 4150);
DISPLAY INVISIBLE (-5425 4150);
FORCEPROP 1 LAST PATH I207
J 0
(-5375 4300);
DISPLAY 0.978723 (-5375 4300);
PAINT WHITE (-5375 4300);
DISPLAY INVISIBLE (-5375 4300);
FORCEPROP 2 LAST CDS_LOCATION C3M9
J 0
(-5375 4250);
DISPLAY 0.617021 (-5375 4250);
PAINT AQUA (-5375 4250);
DISPLAY INVISIBLE (-5375 4250);
FORCEPROP 2 LAST CDS_SEC 1
J 0
(-5375 4350);
DISPLAY 1.042553 (-5375 4350);
PAINT ORANGE (-5375 4350);
DISPLAY INVISIBLE (-5375 4350);
FORCEPROP 2 LAST $SEC 1
J 0
(-5375 4350);
DISPLAY 0.680851 (-5375 4350);
PAINT MONO (-5375 4350);
DISPLAY INVISIBLE (-5375 4350);
FORCEPROP 0 LAST REUSE_ID 1
J 0
(-5375 4350);
DISPLAY 1.042553 (-5375 4350);
PAINT ORANGE (-5375 4350);
DISPLAY INVISIBLE (-5375 4350);
FORCEPROP 0 LAST FIN VR_1P2
J 0
(-5375 4450);
PAINT ORANGE (-5375 4450);
DISPLAY INVISIBLE (-5375 4450);
FORCEADD GND..1
(-3975 475);
FORCEPROP 3 LASTPIN (-3975 525) SIG_NAME GND\g
J 0
(-3965 535);
DISPLAY 0.659574 (-3965 535);
PAINT MONO (-3965 535);
DISPLAY INVISIBLE (-3965 535);
FORCEPROP 2 LAST BOM_COST PVPP_KLM_VR
J 0
(-4875 625);
DISPLAY 1.042553 (-4875 625);
PAINT WHITE (-4875 625);
DISPLAY INVISIBLE (-4875 625);
FORCEPROP 2 LAST ROOM PVPP_KLM_VR
J 0
(-4625 625);
PAINT GREEN (-4625 625);
DISPLAY INVISIBLE (-4625 625);
FORCEPROP 1 LAST PATH I208
J 0
(-3900 475);
DISPLAY 0.872340 (-3900 475);
PAINT AQUA (-3900 475);
DISPLAY INVISIBLE (-3900 475);
FORCEPROP 1 LAST SIZE 1B
J 0
(-3900 500);
DISPLAY 0.893617 (-3900 500);
PAINT GREEN (-3900 500);
DISPLAY INVISIBLE (-3900 500);
FORCEPROP 1 LAST VOLTAGE 0
J 0
(-3975 550);
PAINT SKYBLUE (-3975 550);
DISPLAY INVISIBLE (-3975 550);
FORCEPROP 2 LAST CDS_LIB mstr_symbols
J 0
(-3975 550);
PAINT MONO (-3975 550);
DISPLAY INVISIBLE (-3975 550);
FORCEPROP 1 LAST BODY_TYPE PLUMBING
J 0
(-4020 432);
DISPLAY 0.340426 (-4020 432);
PAINT GREEN (-4020 432);
DISPLAY INVISIBLE (-4020 432);
FORCEPROP 1 LAST HDL_POWER GND
J 0
(-3975 700);
DISPLAY 0.893617 (-3975 700);
PAINT GREEN (-3975 700);
DISPLAY INVISIBLE (-3975 700);
FORCEADD CAP..1
(-3975 725);
FORCEPROP 1 LASTPIN (-3975 625) $PN 2
J 0
(-3965 605);
DISPLAY 0.617021 (-3965 605);
PAINT WHITE (-3965 605);
FORCEPROP 1 LAST LOCATION C7B12
J 0
(-3925 825);
DISPLAY 0.617021 (-3925 825);
PAINT AQUA (-3925 825);
FORCEPROP 1 LAST PART_NUMBER A36096-046
J 0
(-3925 525);
DISPLAY 0.617021 (-3925 525);
PAINT BLUE (-3925 525);
FORCEPROP 1 LAST PACK_TYPE 0402LF
J 0
(-3925 575);
DISPLAY 0.617021 (-3925 575);
PAINT SKYBLUE (-3925 575);
FORCEPROP 1 LAST MATERIAL X7R
J 0
(-3925 625);
DISPLAY 0.617021 (-3925 625);
PAINT SKYBLUE (-3925 625);
FORCEPROP 1 LAST TOLERANCE 10%
J 0
(-3925 675);
DISPLAY 0.617021 (-3925 675);
PAINT SKYBLUE (-3925 675);
FORCEPROP 1 LAST VOLTAGE 50V
J 0
(-3925 725);
DISPLAY 0.617021 (-3925 725);
PAINT SKYBLUE (-3925 725);
FORCEPROP 1 LAST VALUE 1000PF
J 0
(-3925 775);
DISPLAY 0.617021 (-3925 775);
PAINT SKYBLUE (-3925 775);
FORCEPROP 1 LASTPIN (-3975 825) $PN 1
J 0
(-3965 805);
DISPLAY 0.617021 (-3965 805);
PAINT WHITE (-3965 805);
FORCEPROP 2 LAST ROOM PVPP_KLM_VR
J 0
(-3975 725);
PAINT GREEN (-3975 725);
DISPLAY INVISIBLE (-3975 725);
FORCEPROP 2 LAST BOM_COST PVPP_KLM_VR
J 0
(-3975 725);
PAINT WHITE (-3975 725);
DISPLAY INVISIBLE (-3975 725);
FORCEPROP 2 LAST CDS_LIB mstr_discrete
J 2
(-3975 725);
PAINT MONO (-3975 725);
DISPLAY INVISIBLE (-3975 725);
FORCEPROP 1 LAST PATH I209
J 0
(-3925 875);
DISPLAY 0.978723 (-3925 875);
PAINT WHITE (-3925 875);
DISPLAY INVISIBLE (-3925 875);
FORCEPROP 2 LAST CDS_LOCATION C7B12
J 0
(-3925 825);
DISPLAY 0.617021 (-3925 825);
PAINT AQUA (-3925 825);
DISPLAY INVISIBLE (-3925 825);
FORCEPROP 2 LAST CDS_SEC 1
J 2
(-3925 925);
DISPLAY 1.042553 (-3925 925);
PAINT ORANGE (-3925 925);
DISPLAY INVISIBLE (-3925 925);
FORCEPROP 2 LAST $SEC 1
J 2
(-3925 925);
DISPLAY 0.680851 (-3925 925);
PAINT MONO (-3925 925);
DISPLAY INVISIBLE (-3925 925);
FORCEPROP 2 LAST REUSE_ID 17
J 0
(-3925 925);
DISPLAY 1.042553 (-3925 925);
PAINT ORANGE (-3925 925);
DISPLAY INVISIBLE (-3925 925);
FORCEADD RES..2
(-4575 1250);
FORCEPROP 1 LASTPIN (-4575 1350) $PN 1
J 0
(-4570 1312);
DISPLAY 0.617021 (-4570 1312);
PAINT WHITE (-4570 1312);
FORCEPROP 1 LAST PACK_TYPE 0402
J 0
(-4535 1075);
DISPLAY 0.617021 (-4535 1075);
PAINT SKYBLUE (-4535 1075);
FORCEPROP 1 LAST PART_NUMBER G21796-026
J 0
(-4535 1125);
DISPLAY 0.617021 (-4535 1125);
PAINT BLUE (-4535 1125);
FORCEPROP 1 LASTPIN (-4575 1150) $PN 2
J 0
(-4570 1160);
DISPLAY 0.617021 (-4570 1160);
PAINT WHITE (-4570 1160);
FORCEPROP 1 LAST VALUE 1.00K
J 0
(-4530 1325);
DISPLAY 0.617021 (-4530 1325);
PAINT SKYBLUE (-4530 1325);
FORCEPROP 1 LAST MATERIAL CHIP
J 0
(-4535 1175);
DISPLAY 0.617021 (-4535 1175);
PAINT SKYBLUE (-4535 1175);
FORCEPROP 1 LAST WATTAGE 1/16W
J 0
(-4535 1225);
DISPLAY 0.617021 (-4535 1225);
PAINT SKYBLUE (-4535 1225);
FORCEPROP 1 LAST LOCATION R7B17
J 0
(-4530 1375);
DISPLAY 0.617021 (-4530 1375);
PAINT AQUA (-4530 1375);
FORCEPROP 1 LAST TOLERANCE 1%
J 0
(-4530 1275);
DISPLAY 0.617021 (-4530 1275);
PAINT SKYBLUE (-4530 1275);
FORCEPROP 2 LAST REUSE_ID 21
J 0
(-4525 1475);
DISPLAY 1.042553 (-4525 1475);
PAINT ORANGE (-4525 1475);
DISPLAY INVISIBLE (-4525 1475);
FORCEPROP 2 LAST SEC_TYPE 0402
J 0
(-4525 1475);
DISPLAY 1.042553 (-4525 1475);
PAINT ORANGE (-4525 1475);
DISPLAY INVISIBLE (-4525 1475);
FORCEPROP 2 LAST BOM_COST PVPP_KLM_VR
J 0
(-4515 1440);
DISPLAY 1.042553 (-4515 1440);
PAINT WHITE (-4515 1440);
DISPLAY INVISIBLE (-4515 1440);
FORCEPROP 2 LAST SEC 1
J 0
(-4525 1475);
DISPLAY 0.680851 (-4525 1475);
PAINT MONO (-4525 1475);
DISPLAY INVISIBLE (-4525 1475);
FORCEPROP 1 LAST PATH I210
J 0
(-4525 1425);
DISPLAY 0.978723 (-4525 1425);
PAINT WHITE (-4525 1425);
DISPLAY INVISIBLE (-4525 1425);
FORCEPROP 2 LAST ROOM PVPP_KLM_VR
J 0
(-4515 1415);
PAINT GREEN (-4515 1415);
DISPLAY INVISIBLE (-4515 1415);
FORCEPROP 2 LAST CDS_LOCATION R7B17
J 0
(-4530 1375);
DISPLAY 0.617021 (-4530 1375);
PAINT AQUA (-4530 1375);
DISPLAY INVISIBLE (-4530 1375);
FORCEPROP 2 LAST CDS_LIB mstr_discrete
J 0
(-4575 1250);
PAINT MONO (-4575 1250);
DISPLAY INVISIBLE (-4575 1250);
FORCEADD P3V3_STBY..1
(-4575 1525);
FORCEPROP 3 LASTPIN (-4575 1475) SIG_NAME P3V3_STBY\g
J 0
(-4565 1485);
DISPLAY 0.659574 (-4565 1485);
PAINT MONO (-4565 1485);
DISPLAY INVISIBLE (-4565 1485);
FORCEPROP 1 LAST VOLTAGE +3.3V
J 0
(-4375 1675);
DISPLAY 1.021277 (-4375 1675);
PAINT SKYBLUE (-4375 1675);
DISPLAY INVISIBLE (-4375 1675);
FORCEPROP 1 LAST SIZE 1B
J 0
(-4530 1547);
DISPLAY 0.340426 (-4530 1547);
PAINT GREEN (-4530 1547);
DISPLAY INVISIBLE (-4530 1547);
FORCEPROP 2 LAST CDS_LIB mstr_symbols
J 0
(-4575 1525);
PAINT MONO (-4575 1525);
DISPLAY INVISIBLE (-4575 1525);
FORCEPROP 1 LAST PATH I211
J 0
(-4530 1527);
DISPLAY 0.340426 (-4530 1527);
PAINT GREEN (-4530 1527);
DISPLAY INVISIBLE (-4530 1527);
FORCEPROP 1 LAST BODY_TYPE PLUMBING
J 0
(-4620 1482);
DISPLAY 0.340426 (-4620 1482);
PAINT GREEN (-4620 1482);
DISPLAY INVISIBLE (-4620 1482);
FORCEPROP 1 LAST HDL_POWER P3V3_STBY
J 0
(-4875 1400);
DISPLAY 0.872340 (-4875 1400);
PAINT ORANGE (-4875 1400);
DISPLAY INVISIBLE (-4875 1400);
FORCEADD OFFPAGE..2
(-2900 975);
FORCEPROP 2 LAST $XR0 190 
J 0
(-2711 975);
DISPLAY 0.638298 (-2711 975);
PAINT MONO (-2711 975);
FORCEPROP 2 LAST PATH I212
J 0
(-2600 1025);
DISPLAY 1.021277 (-2600 1025);
PAINT ORANGE (-2600 1025);
DISPLAY INVISIBLE (-2600 1025);
FORCEPROP 0 LAST TOLERANCE 1%
J 0
(-2725 1050);
PAINT SKYBLUE (-2725 1050);
DISPLAY INVISIBLE (-2725 1050);
FORCEPROP 2 LAST CDS_LIB mstr_standard
J 2
(-2900 975);
PAINT MONO (-2900 975);
DISPLAY INVISIBLE (-2900 975);
FORCEPROP 2 LAST ROOM PVPP_KLM_VR
J 0
(-3325 1050);
DISPLAY 1.042553 (-3325 1050);
PAINT GREEN (-3325 1050);
DISPLAY INVISIBLE (-3325 1050);
FORCEPROP 2 LAST BOM_COST PVPP_KLM_VR
J 0
(-3600 1050);
DISPLAY 1.042553 (-3600 1050);
PAINT WHITE (-3600 1050);
DISPLAY INVISIBLE (-3600 1050);
FORCEPROP 1 LAST OFFPAGE TRUE
J 0
(-2575 850);
PAINT GREEN (-2575 850);
DISPLAY INVISIBLE (-2575 850);
FORCEPROP 1 LAST COMMENT_BODY TRUE
J 0
(-2945 880);
DISPLAY 0.872340 (-2945 880);
PAINT PEACH (-2945 880);
DISPLAY INVISIBLE (-2945 880);
FORCEADD NCP3232L..1
(-4150 2875);
FORCEPROP 2 LASTPIN (-4650 3225) $PN 10
J 2
(-4660 3235);
DISPLAY 0.617021 (-4660 3235);
PAINT ORANGE (-4660 3235);
FORCEPROP 2 LASTPIN (-4650 3275) $PN 11
J 2
(-4660 3285);
DISPLAY 0.617021 (-4660 3285);
PAINT ORANGE (-4660 3285);
FORCEPROP 2 LASTPIN (-3650 3475) $PN 43
J 0
(-3640 3485);
DISPLAY 0.617021 (-3640 3485);
PAINT ORANGE (-3640 3485);
FORCEPROP 2 LASTPIN (-3650 3425) $PN 34
J 0
(-3640 3435);
DISPLAY 0.617021 (-3640 3435);
PAINT ORANGE (-3640 3435);
FORCEPROP 2 LASTPIN (-3650 3375) $PN 33
J 0
(-3640 3385);
DISPLAY 0.617021 (-3640 3385);
PAINT ORANGE (-3640 3385);
FORCEPROP 2 LASTPIN (-3650 3275) $PN 31
J 0
(-3640 3285);
DISPLAY 0.617021 (-3640 3285);
PAINT ORANGE (-3640 3285);
FORCEPROP 2 LASTPIN (-3650 3225) $PN 30
J 0
(-3640 3235);
DISPLAY 0.617021 (-3640 3235);
PAINT ORANGE (-3640 3235);
FORCEPROP 2 LASTPIN (-3650 3175) $PN 29
J 0
(-3640 3185);
DISPLAY 0.617021 (-3640 3185);
PAINT ORANGE (-3640 3185);
FORCEPROP 2 LASTPIN (-3650 3125) $PN 15
J 0
(-3640 3135);
DISPLAY 0.617021 (-3640 3135);
PAINT ORANGE (-3640 3135);
FORCEPROP 2 LASTPIN (-3650 2725) $PN 37
J 0
(-3640 2735);
DISPLAY 0.617021 (-3640 2735);
PAINT ORANGE (-3640 2735);
FORCEPROP 2 LASTPIN (-3650 2675) $PN 28
J 0
(-3640 2685);
DISPLAY 0.617021 (-3640 2685);
PAINT ORANGE (-3640 2685);
FORCEPROP 2 LASTPIN (-3650 2625) $PN 27
J 0
(-3640 2635);
DISPLAY 0.617021 (-3640 2635);
PAINT ORANGE (-3640 2635);
FORCEPROP 2 LASTPIN (-3650 2575) $PN 26
J 0
(-3640 2585);
DISPLAY 0.617021 (-3640 2585);
PAINT ORANGE (-3640 2585);
FORCEPROP 2 LASTPIN (-3650 2525) $PN 25
J 0
(-3640 2535);
DISPLAY 0.617021 (-3640 2535);
PAINT ORANGE (-3640 2535);
FORCEPROP 2 LASTPIN (-3650 2475) $PN 24
J 0
(-3640 2485);
DISPLAY 0.617021 (-3640 2485);
PAINT ORANGE (-3640 2485);
FORCEPROP 2 LASTPIN (-3650 2425) $PN 23
J 0
(-3640 2435);
DISPLAY 0.617021 (-3640 2435);
PAINT ORANGE (-3640 2435);
FORCEPROP 2 LASTPIN (-3650 2375) $PN 22
J 0
(-3640 2385);
DISPLAY 0.617021 (-3640 2385);
PAINT ORANGE (-3640 2385);
FORCEPROP 2 LASTPIN (-3650 2325) $PN 21
J 0
(-3640 2335);
DISPLAY 0.617021 (-3640 2335);
PAINT ORANGE (-3640 2335);
FORCEPROP 2 LASTPIN (-3650 2225) $PN 19
J 0
(-3640 2235);
DISPLAY 0.617021 (-3640 2235);
PAINT ORANGE (-3640 2235);
FORCEPROP 2 LASTPIN (-3650 2175) $PN 18
J 0
(-3640 2185);
DISPLAY 0.617021 (-3640 2185);
PAINT ORANGE (-3640 2185);
FORCEPROP 2 LASTPIN (-3650 2125) $PN 17
J 0
(-3640 2135);
DISPLAY 0.617021 (-3640 2135);
PAINT ORANGE (-3640 2135);
FORCEPROP 2 LASTPIN (-3650 2075) $PN 16
J 0
(-3640 2085);
DISPLAY 0.617021 (-3640 2085);
PAINT ORANGE (-3640 2085);
FORCEPROP 2 LASTPIN (-3650 2925) $PN 2
J 0
(-3640 2935);
DISPLAY 0.617021 (-3640 2935);
PAINT ORANGE (-3640 2935);
FORCEPROP 2 LASTPIN (-3650 2825) $PN 3
J 0
(-3640 2835);
DISPLAY 0.617021 (-3640 2835);
PAINT ORANGE (-3640 2835);
FORCEPROP 2 LASTPIN (-3650 2025) $PN 41
J 0
(-3640 2035);
DISPLAY 0.617021 (-3640 2035);
PAINT ORANGE (-3640 2035);
FORCEPROP 2 LASTPIN (-4650 3325) $PN 12
J 2
(-4660 3335);
DISPLAY 0.617021 (-4660 3335);
PAINT ORANGE (-4660 3335);
FORCEPROP 2 LASTPIN (-4650 3375) $PN 13
J 2
(-4660 3385);
DISPLAY 0.617021 (-4660 3385);
PAINT ORANGE (-4660 3385);
FORCEPROP 2 LASTPIN (-4650 3425) $PN 14
J 2
(-4660 3435);
DISPLAY 0.617021 (-4660 3435);
PAINT ORANGE (-4660 3435);
FORCEPROP 2 LASTPIN (-4650 3475) $PN 42
J 2
(-4660 3485);
DISPLAY 0.617021 (-4660 3485);
PAINT ORANGE (-4660 3485);
FORCEPROP 2 LASTPIN (-4650 3125) $PN 8
J 2
(-4660 3135);
DISPLAY 0.617021 (-4660 3135);
PAINT ORANGE (-4660 3135);
FORCEPROP 2 LASTPIN (-4650 3175) $PN 9
J 2
(-4660 3185);
DISPLAY 0.617021 (-4660 3185);
PAINT ORANGE (-4660 3185);
FORCEPROP 2 LASTPIN (-4650 2925) $PN 6
J 2
(-4660 2935);
DISPLAY 0.617021 (-4660 2935);
PAINT ORANGE (-4660 2935);
FORCEPROP 2 LASTPIN (-4650 2625) $PN 4
J 2
(-4660 2635);
DISPLAY 0.617021 (-4660 2635);
PAINT ORANGE (-4660 2635);
FORCEPROP 2 LASTPIN (-4650 2825) $PN 40
J 2
(-4660 2835);
DISPLAY 0.617021 (-4660 2835);
PAINT ORANGE (-4660 2835);
FORCEPROP 2 LASTPIN (-4650 2525) $PN 7
J 2
(-4660 2535);
DISPLAY 0.617021 (-4660 2535);
PAINT ORANGE (-4660 2535);
FORCEPROP 2 LASTPIN (-4650 2025) $PN 5
J 2
(-4660 2035);
DISPLAY 0.617021 (-4660 2035);
PAINT ORANGE (-4660 2035);
FORCEPROP 2 LASTPIN (-3650 3025) $PN 35
J 0
(-3640 3035);
DISPLAY 0.617021 (-3640 3035);
PAINT ORANGE (-3640 3035);
FORCEPROP 2 LASTPIN (-3650 3575) $PN 36
J 0
(-3640 3585);
DISPLAY 0.617021 (-3640 3585);
PAINT ORANGE (-3640 3585);
FORCEPROP 2 LASTPIN (-3650 3325) $PN 32
J 0
(-3640 3335);
DISPLAY 0.617021 (-3640 3335);
PAINT ORANGE (-3640 3335);
FORCEPROP 2 LASTPIN (-4650 2725) $PN 1
J 2
(-4660 2735);
DISPLAY 0.617021 (-4660 2735);
PAINT ORANGE (-4660 2735);
FORCEPROP 2 LASTPIN (-4650 3575) $PN 39
J 2
(-4660 3585);
DISPLAY 0.617021 (-4660 3585);
PAINT ORANGE (-4660 3585);
FORCEPROP 1 LAST MATERIAL IC
J 0
(-4600 3775);
DISPLAY 0.617021 (-4600 3775);
PAINT SKYBLUE (-4600 3775);
FORCEPROP 1 LAST LOCATION EU7B1
J 0
(-4600 3825);
DISPLAY 0.617021 (-4600 3825);
PAINT AQUA (-4600 3825);
FORCEPROP 2 LASTPIN (-4650 3025) $PN 38
J 2
(-4660 3035);
DISPLAY 0.617021 (-4660 3035);
PAINT ORANGE (-4660 3035);
FORCEPROP 2 LASTPIN (-3650 2275) $PN 20
J 0
(-3640 2285);
DISPLAY 0.617021 (-3640 2285);
PAINT ORANGE (-3640 2285);
FORCEPROP 1 LAST PART_NUMBER H86355-001
J 0
(-4600 1875);
DISPLAY 0.617021 (-4600 1875);
PAINT BLUE (-4600 1875);
FORCEPROP 1 LAST PATH I214
J 0
(-4100 3775);
PAINT GREEN (-4100 3775);
DISPLAY INVISIBLE (-4100 3775);
FORCEPROP 2 LAST CDS_LOCATION EU7B1
J 0
(-4600 3825);
DISPLAY 0.617021 (-4600 3825);
PAINT AQUA (-4600 3825);
DISPLAY INVISIBLE (-4600 3825);
FORCEPROP 2 LAST SEC 1
J 0
(-4600 3875);
DISPLAY 0.680851 (-4600 3875);
PAINT MONO (-4600 3875);
DISPLAY INVISIBLE (-4600 3875);
FORCEPROP 2 LAST SEC_TYPE SM
J 0
(-4600 3875);
DISPLAY 1.021277 (-4600 3875);
PAINT ORANGE (-4600 3875);
DISPLAY INVISIBLE (-4600 3875);
FORCEPROP 1 LAST PACK_TYPE SM
J 0
(-4600 3875);
PAINT SKYBLUE (-4600 3875);
DISPLAY INVISIBLE (-4600 3875);
FORCEPROP 1 LAST CDS_LMAN_SYM_OUTLINE -450,850,450,-900
J 0
(-4150 2875);
DISPLAY 0.468085 (-4150 2875);
PAINT GREEN (-4150 2875);
DISPLAY INVISIBLE (-4150 2875);
FORCEPROP 2 LAST CDS_LIB mstr_vreg
J 0
(-4150 2875);
PAINT ORANGE (-4150 2875);
DISPLAY INVISIBLE (-4150 2875);
FORCEADD GND..1
(-3425 1925);
FORCEPROP 3 LASTPIN (-3425 1975) SIG_NAME GND\g
J 0
(-3415 1985);
DISPLAY 0.659574 (-3415 1985);
PAINT MONO (-3415 1985);
DISPLAY INVISIBLE (-3415 1985);
FORCEPROP 2 LAST ROOM PVPP_KLM_VR
J 0
(-4075 2075);
PAINT GREEN (-4075 2075);
DISPLAY INVISIBLE (-4075 2075);
FORCEPROP 1 LAST SIZE 1B
J 0
(-3350 1950);
DISPLAY 0.893617 (-3350 1950);
PAINT GREEN (-3350 1950);
DISPLAY INVISIBLE (-3350 1950);
FORCEPROP 1 LAST PATH I215
J 0
(-3350 1925);
DISPLAY 0.872340 (-3350 1925);
PAINT AQUA (-3350 1925);
DISPLAY INVISIBLE (-3350 1925);
FORCEPROP 1 LAST VOLTAGE 0
J 0
(-3425 2000);
PAINT SKYBLUE (-3425 2000);
DISPLAY INVISIBLE (-3425 2000);
FORCEPROP 2 LAST CDS_LIB mstr_symbols
J 0
(-3425 1925);
PAINT MONO (-3425 1925);
DISPLAY INVISIBLE (-3425 1925);
FORCEPROP 2 LAST BOM_COST PVPP_KLM_VR
J 0
(-4325 2075);
DISPLAY 1.042553 (-4325 2075);
PAINT WHITE (-4325 2075);
DISPLAY INVISIBLE (-4325 2075);
FORCEPROP 1 LAST BODY_TYPE PLUMBING
J 0
(-3470 1882);
DISPLAY 0.340426 (-3470 1882);
PAINT GREEN (-3470 1882);
DISPLAY INVISIBLE (-3470 1882);
FORCEPROP 1 LAST HDL_POWER GND
J 0
(-3425 2150);
DISPLAY 0.893617 (-3425 2150);
PAINT GREEN (-3425 2150);
DISPLAY INVISIBLE (-3425 2150);
FORCEADD RES..2
(-2875 3325);
FORCEPROP 1 LAST TOLERANCE 5%
J 0
(-2780 3350);
DISPLAY 0.617021 (-2780 3350);
PAINT SKYBLUE (-2780 3350);
FORCEPROP 1 LAST LOCATION R7A15
J 0
(-2830 3400);
DISPLAY 0.617021 (-2830 3400);
PAINT AQUA (-2830 3400);
FORCEPROP 1 LASTPIN (-2875 3425) $PN 1
J 0
(-2870 3387);
DISPLAY 0.617021 (-2870 3387);
PAINT WHITE (-2870 3387);
FORCEPROP 1 LASTPIN (-2875 3225) $PN 2
J 0
(-2870 3235);
DISPLAY 0.617021 (-2870 3235);
PAINT WHITE (-2870 3235);
FORCEPROP 1 LAST VALUE 2.2
J 0
(-2680 3400);
DISPLAY 0.617021 (-2680 3400);
PAINT SKYBLUE (-2680 3400);
FORCEPROP 1 LAST MATERIAL EMPTY
J 0
(-2710 3350);
DISPLAY 0.617021 (-2710 3350);
PAINT RED (-2710 3350);
FORCEPROP 1 LAST PACK_TYPE 0402
J 0
(-2785 3250);
DISPLAY 0.617021 (-2785 3250);
PAINT SKYBLUE (-2785 3250);
FORCEPROP 1 LAST WATTAGE 1/16W
J 0
(-2760 3300);
DISPLAY 0.617021 (-2760 3300);
PAINT SKYBLUE (-2760 3300);
FORCEPROP 1 LAST PART_NUMBER G21497-016
J 0
(-2785 3200);
DISPLAY 0.617021 (-2785 3200);
PAINT BLUE (-2785 3200);
FORCEPROP 2 LAST SEC_TYPE 0402
J 0
(-2825 3550);
DISPLAY 1.021277 (-2825 3550);
PAINT ORANGE (-2825 3550);
DISPLAY INVISIBLE (-2825 3550);
FORCEPROP 2 LAST REUSE_ID 29
J 0
(-2825 3550);
DISPLAY 1.042553 (-2825 3550);
PAINT ORANGE (-2825 3550);
DISPLAY INVISIBLE (-2825 3550);
FORCEPROP 2 LAST SEC 1
J 0
(-2825 3550);
DISPLAY 0.680851 (-2825 3550);
PAINT MONO (-2825 3550);
DISPLAY INVISIBLE (-2825 3550);
FORCEPROP 2 LAST BOM_COST PVPP_KLM_VR
J 0
(-2825 3500);
DISPLAY 1.042553 (-2825 3500);
PAINT WHITE (-2825 3500);
DISPLAY INVISIBLE (-2825 3500);
FORCEPROP 1 LAST PATH I218
J 0
(-2825 3500);
DISPLAY 0.978723 (-2825 3500);
PAINT WHITE (-2825 3500);
DISPLAY INVISIBLE (-2825 3500);
FORCEPROP 2 LAST ROOM PVPP_KLM_VR
J 0
(-2825 3475);
PAINT GREEN (-2825 3475);
DISPLAY INVISIBLE (-2825 3475);
FORCEPROP 2 LAST CDS_LOCATION R7A15
J 0
(-2830 3425);
DISPLAY 0.617021 (-2830 3425);
PAINT AQUA (-2830 3425);
DISPLAY INVISIBLE (-2830 3425);
FORCEPROP 2 LAST CDS_LIB mstr_discrete
J 0
(-2875 3325);
PAINT MONO (-2875 3325);
DISPLAY INVISIBLE (-2875 3325);
FORCEADD GND..1
(-2875 3150);
FORCEPROP 3 LASTPIN (-2875 3200) SIG_NAME GND\g
J 0
(-2865 3210);
DISPLAY 0.659574 (-2865 3210);
PAINT MONO (-2865 3210);
DISPLAY INVISIBLE (-2865 3210);
FORCEPROP 2 LAST BOM_COST PVPP_KLM_VR
J 0
(-3775 3300);
DISPLAY 1.042553 (-3775 3300);
PAINT WHITE (-3775 3300);
DISPLAY INVISIBLE (-3775 3300);
FORCEPROP 2 LAST ROOM PVPP_KLM_VR
J 0
(-3525 3300);
PAINT GREEN (-3525 3300);
DISPLAY INVISIBLE (-3525 3300);
FORCEPROP 2 LAST CDS_LIB mstr_symbols
J 0
(-2875 3225);
PAINT MONO (-2875 3225);
DISPLAY INVISIBLE (-2875 3225);
FORCEPROP 1 LAST VOLTAGE 0
J 0
(-2875 3225);
PAINT SKYBLUE (-2875 3225);
DISPLAY INVISIBLE (-2875 3225);
FORCEPROP 1 LAST PATH I219
J 0
(-2800 3150);
DISPLAY 0.872340 (-2800 3150);
PAINT AQUA (-2800 3150);
DISPLAY INVISIBLE (-2800 3150);
FORCEPROP 1 LAST SIZE 1B
J 0
(-2800 3175);
DISPLAY 0.893617 (-2800 3175);
PAINT GREEN (-2800 3175);
DISPLAY INVISIBLE (-2800 3175);
FORCEPROP 1 LAST BODY_TYPE PLUMBING
J 0
(-2920 3107);
DISPLAY 0.340426 (-2920 3107);
PAINT GREEN (-2920 3107);
DISPLAY INVISIBLE (-2920 3107);
FORCEPROP 1 LAST HDL_POWER GND
J 0
(-2875 3375);
DISPLAY 0.893617 (-2875 3375);
PAINT GREEN (-2875 3375);
DISPLAY INVISIBLE (-2875 3375);
FORCEADD CAP..1
(-2875 3700);
FORCEPROP 1 LASTPIN (-2875 3600) $PN 2
J 0
(-2865 3580);
DISPLAY 0.617021 (-2865 3580);
PAINT WHITE (-2865 3580);
FORCEPROP 1 LAST TOLERANCE 10%
J 0
(-2750 3650);
DISPLAY 0.617021 (-2750 3650);
PAINT SKYBLUE (-2750 3650);
FORCEPROP 1 LASTPIN (-2875 3800) $PN 1
J 0
(-2865 3780);
DISPLAY 0.617021 (-2865 3780);
PAINT WHITE (-2865 3780);
FORCEPROP 1 LAST LOCATION C7A34
J 0
(-2775 3800);
DISPLAY 0.617021 (-2775 3800);
PAINT AQUA (-2775 3800);
FORCEPROP 1 LAST VALUE 3300PF
J 0
(-2750 3750);
DISPLAY 0.617021 (-2750 3750);
PAINT SKYBLUE (-2750 3750);
FORCEPROP 1 LAST VOLTAGE 50V
J 0
(-2750 3700);
DISPLAY 0.617021 (-2750 3700);
PAINT SKYBLUE (-2750 3700);
FORCEPROP 1 LAST MATERIAL EMPTY
J 0
(-2650 3675);
DISPLAY 0.617021 (-2650 3675);
PAINT RED (-2650 3675);
FORCEPROP 1 LAST PACK_TYPE 0402LF
J 0
(-2750 3600);
DISPLAY 0.617021 (-2750 3600);
PAINT SKYBLUE (-2750 3600);
FORCEPROP 1 LAST PART_NUMBER A36096-091
J 0
(-2750 3550);
DISPLAY 0.617021 (-2750 3550);
PAINT BLUE (-2750 3550);
FORCEPROP 2 LAST SEC_TYPE 0402LF
J 0
(-2825 3900);
DISPLAY 1.021277 (-2825 3900);
PAINT ORANGE (-2825 3900);
DISPLAY INVISIBLE (-2825 3900);
FORCEPROP 2 LAST REUSE_ID 26
J 0
(-2825 3900);
DISPLAY 1.042553 (-2825 3900);
PAINT ORANGE (-2825 3900);
DISPLAY INVISIBLE (-2825 3900);
FORCEPROP 2 LAST BOM_COST PVPP_KLM_VR
J 0
(-2825 3850);
DISPLAY 1.042553 (-2825 3850);
PAINT WHITE (-2825 3850);
DISPLAY INVISIBLE (-2825 3850);
FORCEPROP 2 LAST SEC 1
J 0
(-2825 3900);
DISPLAY 0.680851 (-2825 3900);
PAINT MONO (-2825 3900);
DISPLAY INVISIBLE (-2825 3900);
FORCEPROP 1 LAST PATH I220
J 0
(-2825 3850);
DISPLAY 0.978723 (-2825 3850);
PAINT WHITE (-2825 3850);
DISPLAY INVISIBLE (-2825 3850);
FORCEPROP 2 LAST ROOM PVPP_KLM_VR
J 0
(-2825 3825);
PAINT GREEN (-2825 3825);
DISPLAY INVISIBLE (-2825 3825);
FORCEPROP 2 LAST CDS_LOCATION C7A34
J 0
(-2775 3800);
DISPLAY 0.617021 (-2775 3800);
PAINT AQUA (-2775 3800);
DISPLAY INVISIBLE (-2775 3800);
FORCEPROP 2 LAST CDS_LIB mstr_discrete
J 0
(-2875 3700);
PAINT MONO (-2875 3700);
DISPLAY INVISIBLE (-2875 3700);
FORCEADD GND..1
(-2400 3400);
FORCEPROP 3 LASTPIN (-2400 3450) SIG_NAME GND\g
J 0
(-2390 3460);
DISPLAY 0.659574 (-2390 3460);
PAINT MONO (-2390 3460);
DISPLAY INVISIBLE (-2390 3460);
FORCEPROP 2 LAST BOM_COST PVPP_KLM_VR
J 0
(-3250 3475);
DISPLAY 1.042553 (-3250 3475);
PAINT WHITE (-3250 3475);
DISPLAY INVISIBLE (-3250 3475);
FORCEPROP 2 LAST ROOM PVPP_KLM_VR
J 0
(-2975 3475);
DISPLAY 1.042553 (-2975 3475);
PAINT GREEN (-2975 3475);
DISPLAY INVISIBLE (-2975 3475);
FORCEPROP 1 LAST PATH I226
J 0
(-2325 3400);
DISPLAY 0.872340 (-2325 3400);
PAINT AQUA (-2325 3400);
DISPLAY INVISIBLE (-2325 3400);
FORCEPROP 1 LAST SIZE 1B
J 0
(-2325 3350);
DISPLAY 0.872340 (-2325 3350);
PAINT GREEN (-2325 3350);
DISPLAY INVISIBLE (-2325 3350);
FORCEPROP 2 LAST CDS_LIB mstr_symbols
J 0
(-2400 3400);
PAINT MONO (-2400 3400);
DISPLAY INVISIBLE (-2400 3400);
FORCEPROP 1 LAST VOLTAGE 0
J 0
(-2400 3400);
PAINT SKYBLUE (-2400 3400);
DISPLAY INVISIBLE (-2400 3400);
FORCEPROP 1 LAST BODY_TYPE PLUMBING
J 0
(-2445 3357);
DISPLAY 0.340426 (-2445 3357);
PAINT GREEN (-2445 3357);
DISPLAY INVISIBLE (-2445 3357);
FORCEPROP 1 LAST HDL_POWER GND
J 0
(-2400 3550);
DISPLAY 0.872340 (-2400 3550);
PAINT GREEN (-2400 3550);
DISPLAY INVISIBLE (-2400 3550);
FORCEADD RES..2
(-2400 3650);
FORCEPROP 1 LASTPIN (-2400 3550) $PN 2
J 0
(-2395 3560);
DISPLAY 0.617021 (-2395 3560);
PAINT WHITE (-2395 3560);
FORCEPROP 1 LASTPIN (-2400 3750) $PN 1
J 0
(-2395 3712);
DISPLAY 0.617021 (-2395 3712);
PAINT WHITE (-2395 3712);
FORCEPROP 1 LAST VALUE 120.0
J 0
(-2355 3725);
DISPLAY 0.617021 (-2355 3725);
PAINT SKYBLUE (-2355 3725);
FORCEPROP 1 LAST TOLERANCE 1%
J 0
(-2355 3675);
DISPLAY 0.617021 (-2355 3675);
PAINT SKYBLUE (-2355 3675);
FORCEPROP 1 LAST WATTAGE 1/10W
J 0
(-2360 3625);
DISPLAY 0.617021 (-2360 3625);
PAINT SKYBLUE (-2360 3625);
FORCEPROP 1 LAST MATERIAL CHIP
J 0
(-2360 3575);
DISPLAY 0.617021 (-2360 3575);
PAINT SKYBLUE (-2360 3575);
FORCEPROP 1 LAST PART_NUMBER G22026-003
J 0
(-2360 3525);
DISPLAY 0.617021 (-2360 3525);
PAINT BLUE (-2360 3525);
FORCEPROP 1 LAST PACK_TYPE 0603
J 0
(-2360 3475);
DISPLAY 0.617021 (-2360 3475);
PAINT SKYBLUE (-2360 3475);
FORCEPROP 1 LAST LOCATION R7B10
J 0
(-2355 3775);
DISPLAY 0.617021 (-2355 3775);
PAINT AQUA (-2355 3775);
FORCEPROP 1 LAST PATH I227
J 0
(-2350 3825);
DISPLAY 0.978723 (-2350 3825);
PAINT WHITE (-2350 3825);
DISPLAY INVISIBLE (-2350 3825);
FORCEPROP 2 LAST BOM_COST PVPP_KLM_VR
J 0
(-2355 3830);
DISPLAY 1.042553 (-2355 3830);
PAINT WHITE (-2355 3830);
DISPLAY INVISIBLE (-2355 3830);
FORCEPROP 2 LAST REUSE_ID 34
J 0
(-2350 3875);
DISPLAY 1.042553 (-2350 3875);
PAINT ORANGE (-2350 3875);
DISPLAY INVISIBLE (-2350 3875);
FORCEPROP 2 LAST SEC 1
J 0
(-2350 3875);
DISPLAY 0.680851 (-2350 3875);
PAINT MONO (-2350 3875);
DISPLAY INVISIBLE (-2350 3875);
FORCEPROP 2 LAST SEC_TYPE 0603
J 0
(-2350 3875);
DISPLAY 1.021277 (-2350 3875);
PAINT ORANGE (-2350 3875);
DISPLAY INVISIBLE (-2350 3875);
FORCEPROP 2 LAST ROOM PVPP_KLM_VR
J 0
(-2355 3805);
PAINT GREEN (-2355 3805);
DISPLAY INVISIBLE (-2355 3805);
FORCEPROP 2 LAST CDS_LIB mstr_discrete
J 0
(-2400 3650);
PAINT MONO (-2400 3650);
DISPLAY INVISIBLE (-2400 3650);
FORCEPROP 2 LAST CDS_LOCATION R7B10
J 0
(-2355 3775);
DISPLAY 0.617021 (-2355 3775);
PAINT AQUA (-2355 3775);
DISPLAY INVISIBLE (-2355 3775);
FORCEADD GND..1
(-2100 3275);
FORCEPROP 3 LASTPIN (-2100 3325) SIG_NAME GND\g
J 0
(-2090 3335);
DISPLAY 0.659574 (-2090 3335);
PAINT MONO (-2090 3335);
DISPLAY INVISIBLE (-2090 3335);
FORCEPROP 1 LAST HDL_POWER GND
J 0
(-2100 3425);
DISPLAY 0.872340 (-2100 3425);
PAINT GREEN (-2100 3425);
DISPLAY INVISIBLE (-2100 3425);
FORCEPROP 1 LAST BODY_TYPE PLUMBING
J 0
(-2145 3232);
DISPLAY 0.340426 (-2145 3232);
PAINT GREEN (-2145 3232);
DISPLAY INVISIBLE (-2145 3232);
FORCEPROP 2 LAST BOM_COST PVPP_KLM_VR
J 0
(-2950 3350);
DISPLAY 1.042553 (-2950 3350);
PAINT WHITE (-2950 3350);
DISPLAY INVISIBLE (-2950 3350);
FORCEPROP 2 LAST ROOM PVPP_KLM_VR
J 0
(-2675 3350);
DISPLAY 1.042553 (-2675 3350);
PAINT GREEN (-2675 3350);
DISPLAY INVISIBLE (-2675 3350);
FORCEPROP 2 LAST CDS_LIB mstr_symbols
J 0
(-2100 3275);
PAINT MONO (-2100 3275);
DISPLAY INVISIBLE (-2100 3275);
FORCEPROP 1 LAST VOLTAGE 0
J 0
(-2100 3275);
PAINT SKYBLUE (-2100 3275);
DISPLAY INVISIBLE (-2100 3275);
FORCEPROP 1 LAST SIZE 1B
J 0
(-2025 3225);
DISPLAY 0.872340 (-2025 3225);
PAINT GREEN (-2025 3225);
DISPLAY INVISIBLE (-2025 3225);
FORCEPROP 1 LAST PATH I228
J 0
(-2025 3275);
DISPLAY 0.872340 (-2025 3275);
PAINT AQUA (-2025 3275);
DISPLAY INVISIBLE (-2025 3275);
FORCEADD CAPP..1
(-2100 3650);
FORCEPROP 1 LASTPIN (-2100 3750) $PN 1
J 0
(-2090 3735);
DISPLAY 0.617021 (-2090 3735);
PAINT WHITE (-2090 3735);
FORCEPROP 1 LASTPIN (-2100 3550) $PN 2
J 0
(-2090 3535);
DISPLAY 0.617021 (-2090 3535);
PAINT WHITE (-2090 3535);
FORCEPROP 1 LAST TOLERANCE 20%
J 0
(-2050 3700);
DISPLAY 0.617021 (-2050 3700);
PAINT SKYBLUE (-2050 3700);
FORCEPROP 0 LAST GROUP PWR_BULK_CAP
J 0
(-2035 3451);
DISPLAY 0.638298 (-2035 3451);
PAINT BROWN (-2035 3451);
DISPLAY BOTH (-2035 3451);
FORCEPROP 1 LAST PART_NUMBER 724613-042
J 0
(-2050 3500);
DISPLAY 0.617021 (-2050 3500);
PAINT BLUE (-2050 3500);
FORCEPROP 1 LAST PACK_TYPE 7343LF
J 0
(-2050 3550);
DISPLAY 0.617021 (-2050 3550);
PAINT SKYBLUE (-2050 3550);
FORCEPROP 1 LAST MATERIAL POSCAP
J 0
(-2050 3600);
DISPLAY 0.617021 (-2050 3600);
PAINT SKYBLUE (-2050 3600);
FORCEPROP 1 LAST VOLTAGE 6.3V
J 0
(-2050 3650);
DISPLAY 0.617021 (-2050 3650);
PAINT SKYBLUE (-2050 3650);
FORCEPROP 1 LAST VALUE 330UF
J 0
(-2050 3750);
DISPLAY 0.617021 (-2050 3750);
PAINT SKYBLUE (-2050 3750);
FORCEPROP 1 LAST LOCATION C6B7
J 0
(-2050 3800);
DISPLAY 0.617021 (-2050 3800);
PAINT AQUA (-2050 3800);
FORCEPROP 2 LAST BOM_COST PVPP_KLM_VR
J 0
(-2100 3650);
DISPLAY 0.659574 (-2100 3650);
PAINT WHITE (-2100 3650);
DISPLAY INVISIBLE (-2100 3650);
FORCEPROP 2 LAST ROOM PVPP_KLM_VR
J 0
(-2100 3650);
PAINT GREEN (-2100 3650);
DISPLAY INVISIBLE (-2100 3650);
FORCEPROP 2 LAST CDS_LIB mstr_discrete
J 0
(-2100 3650);
PAINT MONO (-2100 3650);
DISPLAY INVISIBLE (-2100 3650);
FORCEPROP 2 LAST CDS_LOCATION C6B7
J 0
(-2050 3750);
DISPLAY 0.617021 (-2050 3750);
PAINT AQUA (-2050 3750);
DISPLAY INVISIBLE (-2050 3750);
FORCEPROP 1 LAST PATH I229
J 0
(-2050 3800);
DISPLAY 0.978723 (-2050 3800);
PAINT ORANGE (-2050 3800);
DISPLAY INVISIBLE (-2050 3800);
FORCEPROP 2 LAST $SEC 1
J 0
(-2050 3850);
DISPLAY 0.680851 (-2050 3850);
PAINT MONO (-2050 3850);
DISPLAY INVISIBLE (-2050 3850);
FORCEPROP 2 LAST CDS_SEC 1
J 0
(-2050 3850);
DISPLAY 1.042553 (-2050 3850);
PAINT ORANGE (-2050 3850);
DISPLAY INVISIBLE (-2050 3850);
FORCEPROP 2 LAST REUSE_ID 28
J 0
(-2050 3850);
DISPLAY 1.042553 (-2050 3850);
PAINT ORANGE (-2050 3850);
DISPLAY INVISIBLE (-2050 3850);
FORCEADD GND..1
(-1475 3425);
FORCEPROP 3 LASTPIN (-1475 3475) SIG_NAME GND\g
J 0
(-1465 3485);
DISPLAY 0.659574 (-1465 3485);
PAINT MONO (-1465 3485);
DISPLAY INVISIBLE (-1465 3485);
FORCEPROP 1 LAST SIZE 1B
J 0
(-1400 3375);
DISPLAY 0.872340 (-1400 3375);
PAINT GREEN (-1400 3375);
DISPLAY INVISIBLE (-1400 3375);
FORCEPROP 1 LAST PATH I235
J 0
(-1400 3425);
DISPLAY 0.872340 (-1400 3425);
PAINT AQUA (-1400 3425);
DISPLAY INVISIBLE (-1400 3425);
FORCEPROP 1 LAST VOLTAGE 0
J 0
(-1475 3425);
PAINT SKYBLUE (-1475 3425);
DISPLAY INVISIBLE (-1475 3425);
FORCEPROP 2 LAST CDS_LIB mstr_symbols
J 0
(-1475 3425);
PAINT MONO (-1475 3425);
DISPLAY INVISIBLE (-1475 3425);
FORCEPROP 2 LAST ROOM PVPP_KLM_VR
J 0
(-2050 3500);
DISPLAY 1.042553 (-2050 3500);
PAINT GREEN (-2050 3500);
DISPLAY INVISIBLE (-2050 3500);
FORCEPROP 2 LAST BOM_COST PVPP_KLM_VR
J 0
(-2325 3500);
DISPLAY 1.042553 (-2325 3500);
PAINT WHITE (-2325 3500);
DISPLAY INVISIBLE (-2325 3500);
FORCEPROP 1 LAST BODY_TYPE PLUMBING
J 0
(-1520 3382);
DISPLAY 0.340426 (-1520 3382);
PAINT GREEN (-1520 3382);
DISPLAY INVISIBLE (-1520 3382);
FORCEPROP 1 LAST HDL_POWER GND
J 0
(-1475 3575);
DISPLAY 0.872340 (-1475 3575);
PAINT GREEN (-1475 3575);
DISPLAY INVISIBLE (-1475 3575);
FORCEADD CAP..1
(-1475 3675);
FORCEPROP 1 LASTPIN (-1475 3575) $PN 2
J 0
(-1465 3555);
DISPLAY 0.617021 (-1465 3555);
PAINT WHITE (-1465 3555);
FORCEPROP 1 LASTPIN (-1475 3775) $PN 1
J 0
(-1465 3755);
DISPLAY 0.617021 (-1465 3755);
PAINT WHITE (-1465 3755);
FORCEPROP 1 LAST TOLERANCE 20%
J 0
(-1425 3625);
DISPLAY 0.617021 (-1425 3625);
PAINT SKYBLUE (-1425 3625);
FORCEPROP 1 LAST MATERIAL X6S
J 0
(-1425 3575);
DISPLAY 0.617021 (-1425 3575);
PAINT SKYBLUE (-1425 3575);
FORCEPROP 1 LAST LOCATION C6B3
J 0
(-1425 3775);
DISPLAY 0.617021 (-1425 3775);
PAINT AQUA (-1425 3775);
FORCEPROP 1 LAST VALUE 47UF
J 0
(-1425 3725);
DISPLAY 0.617021 (-1425 3725);
PAINT SKYBLUE (-1425 3725);
FORCEPROP 1 LAST VOLTAGE 4V
J 0
(-1425 3675);
DISPLAY 0.617021 (-1425 3675);
PAINT SKYBLUE (-1425 3675);
FORCEPROP 0 LAST GROUP PWR_MLCC_CAP
J 0
(-1444 3337);
DISPLAY 0.638298 (-1444 3337);
PAINT BROWN (-1444 3337);
DISPLAY BOTH (-1444 3337);
FORCEPROP 1 LAST PART_NUMBER C95333-006
J 0
(-1425 3525);
DISPLAY 0.617021 (-1425 3525);
PAINT BLUE (-1425 3525);
FORCEPROP 1 LAST PACK_TYPE 0805
J 0
(-1425 3475);
DISPLAY 0.617021 (-1425 3475);
PAINT SKYBLUE (-1425 3475);
FORCEPROP 2 LAST REUSE_ID 33
J 0
(-1425 3875);
DISPLAY 1.042553 (-1425 3875);
PAINT ORANGE (-1425 3875);
DISPLAY INVISIBLE (-1425 3875);
FORCEPROP 2 LAST CDS_SEC 1
J 0
(-1425 3875);
DISPLAY 1.042553 (-1425 3875);
PAINT ORANGE (-1425 3875);
DISPLAY INVISIBLE (-1425 3875);
FORCEPROP 2 LAST $SEC 1
J 0
(-1425 3875);
DISPLAY 0.680851 (-1425 3875);
PAINT MONO (-1425 3875);
DISPLAY INVISIBLE (-1425 3875);
FORCEPROP 1 LAST PATH I236
J 0
(-1425 3825);
DISPLAY 0.978723 (-1425 3825);
PAINT WHITE (-1425 3825);
DISPLAY INVISIBLE (-1425 3825);
FORCEPROP 2 LAST CDS_LOCATION C6B3
J 0
(-1425 3775);
DISPLAY 0.617021 (-1425 3775);
PAINT AQUA (-1425 3775);
DISPLAY INVISIBLE (-1425 3775);
FORCEPROP 2 LAST CDS_LIB mstr_discrete
J 0
(-1475 3675);
PAINT MONO (-1475 3675);
DISPLAY INVISIBLE (-1475 3675);
FORCEPROP 2 LAST BOM_COST PVPP_KLM_VR
J 0
(-1475 3675);
PAINT WHITE (-1475 3675);
DISPLAY INVISIBLE (-1475 3675);
FORCEPROP 2 LAST ROOM PVPP_KLM_VR
J 0
(-1475 3675);
PAINT GREEN (-1475 3675);
DISPLAY INVISIBLE (-1475 3675);
FORCEADD GND..1
(-1200 3400);
FORCEPROP 3 LASTPIN (-1200 3450) SIG_NAME GND\g
J 0
(-1190 3460);
DISPLAY 0.659574 (-1190 3460);
PAINT MONO (-1190 3460);
DISPLAY INVISIBLE (-1190 3460);
FORCEPROP 1 LAST SIZE 1B
J 0
(-1125 3350);
DISPLAY 0.872340 (-1125 3350);
PAINT GREEN (-1125 3350);
DISPLAY INVISIBLE (-1125 3350);
FORCEPROP 1 LAST PATH I237
J 0
(-1125 3400);
DISPLAY 0.872340 (-1125 3400);
PAINT AQUA (-1125 3400);
DISPLAY INVISIBLE (-1125 3400);
FORCEPROP 1 LAST VOLTAGE 0
J 0
(-1200 3400);
PAINT SKYBLUE (-1200 3400);
DISPLAY INVISIBLE (-1200 3400);
FORCEPROP 2 LAST CDS_LIB mstr_symbols
J 0
(-1200 3400);
PAINT MONO (-1200 3400);
DISPLAY INVISIBLE (-1200 3400);
FORCEPROP 2 LAST ROOM PVPP_KLM_VR
J 0
(-1775 3475);
DISPLAY 1.042553 (-1775 3475);
PAINT GREEN (-1775 3475);
DISPLAY INVISIBLE (-1775 3475);
FORCEPROP 2 LAST BOM_COST PVPP_KLM_VR
J 0
(-2050 3475);
DISPLAY 1.042553 (-2050 3475);
PAINT WHITE (-2050 3475);
DISPLAY INVISIBLE (-2050 3475);
FORCEPROP 1 LAST BODY_TYPE PLUMBING
J 0
(-1245 3357);
DISPLAY 0.340426 (-1245 3357);
PAINT GREEN (-1245 3357);
DISPLAY INVISIBLE (-1245 3357);
FORCEPROP 1 LAST HDL_POWER GND
J 0
(-1200 3550);
DISPLAY 0.872340 (-1200 3550);
PAINT GREEN (-1200 3550);
DISPLAY INVISIBLE (-1200 3550);
FORCEADD CAP..1
(-1200 3675);
FORCEPROP 1 LAST LOCATION C7B7
J 0
(-1150 3775);
DISPLAY 0.617021 (-1150 3775);
PAINT AQUA (-1150 3775);
FORCEPROP 1 LASTPIN (-1200 3575) $PN 2
J 0
(-1190 3555);
DISPLAY 0.617021 (-1190 3555);
PAINT WHITE (-1190 3555);
FORCEPROP 1 LASTPIN (-1200 3775) $PN 1
J 0
(-1190 3755);
DISPLAY 0.617021 (-1190 3755);
PAINT WHITE (-1190 3755);
FORCEPROP 1 LAST TOLERANCE 20%
J 0
(-1150 3625);
DISPLAY 0.617021 (-1150 3625);
PAINT SKYBLUE (-1150 3625);
FORCEPROP 1 LAST VALUE 47UF
J 0
(-1150 3725);
DISPLAY 0.617021 (-1150 3725);
PAINT SKYBLUE (-1150 3725);
FORCEPROP 1 LAST VOLTAGE 4V
J 0
(-1150 3675);
DISPLAY 0.617021 (-1150 3675);
PAINT SKYBLUE (-1150 3675);
FORCEPROP 1 LAST MATERIAL X6S
J 0
(-1150 3575);
DISPLAY 0.617021 (-1150 3575);
PAINT SKYBLUE (-1150 3575);
FORCEPROP 0 LAST GROUP PWR_MLCC_CAP
J 0
(-1194 3262);
DISPLAY 0.638298 (-1194 3262);
PAINT BROWN (-1194 3262);
DISPLAY BOTH (-1194 3262);
FORCEPROP 1 LAST PACK_TYPE 0805
J 0
(-1150 3475);
DISPLAY 0.617021 (-1150 3475);
PAINT SKYBLUE (-1150 3475);
FORCEPROP 1 LAST PART_NUMBER C95333-006
J 0
(-1150 3525);
DISPLAY 0.617021 (-1150 3525);
PAINT BLUE (-1150 3525);
FORCEPROP 2 LAST REUSE_ID 33
J 0
(-1150 3875);
DISPLAY 1.042553 (-1150 3875);
PAINT ORANGE (-1150 3875);
DISPLAY INVISIBLE (-1150 3875);
FORCEPROP 2 LAST CDS_SEC 1
J 0
(-1150 3875);
DISPLAY 1.042553 (-1150 3875);
PAINT ORANGE (-1150 3875);
DISPLAY INVISIBLE (-1150 3875);
FORCEPROP 2 LAST $SEC 1
J 0
(-1150 3875);
DISPLAY 0.680851 (-1150 3875);
PAINT MONO (-1150 3875);
DISPLAY INVISIBLE (-1150 3875);
FORCEPROP 1 LAST PATH I238
J 0
(-1150 3825);
DISPLAY 0.978723 (-1150 3825);
PAINT WHITE (-1150 3825);
DISPLAY INVISIBLE (-1150 3825);
FORCEPROP 2 LAST BOM_COST PVPP_KLM_VR
J 0
(-1200 3675);
PAINT WHITE (-1200 3675);
DISPLAY INVISIBLE (-1200 3675);
FORCEPROP 2 LAST CDS_LIB mstr_discrete
J 0
(-1200 3675);
PAINT MONO (-1200 3675);
DISPLAY INVISIBLE (-1200 3675);
FORCEPROP 2 LAST CDS_LOCATION C7B7
J 0
(-1150 3775);
DISPLAY 0.617021 (-1150 3775);
PAINT AQUA (-1150 3775);
DISPLAY INVISIBLE (-1150 3775);
FORCEPROP 2 LAST ROOM PVPP_KLM_VR
J 0
(-1200 3675);
PAINT GREEN (-1200 3675);
DISPLAY INVISIBLE (-1200 3675);
FORCEADD INDUCTOR..1
(-2550 3850);
FORCEPROP 1 LASTPIN (-2450 3850) $PN 2
J 2
(-2440 3860);
DISPLAY 0.617021 (-2440 3860);
PAINT WHITE (-2440 3860);
FORCEPROP 1 LAST LOCATION L7B1
J 0
(-2650 4000);
DISPLAY 0.617021 (-2650 4000);
PAINT AQUA (-2650 4000);
FORCEPROP 1 LAST VALUE 0.47UH
J 2
(-2555 3940);
DISPLAY 0.617021 (-2555 3940);
PAINT SKYBLUE (-2555 3940);
FORCEPROP 1 LASTPIN (-2650 3850) $PN 1
J 0
(-2650 3860);
DISPLAY 0.617021 (-2650 3860);
PAINT WHITE (-2650 3860);
FORCEPROP 1 LAST PACK_TYPE SM
J 0
(-2510 3940);
DISPLAY 0.617021 (-2510 3940);
PAINT SKYBLUE (-2510 3940);
FORCEPROP 1 LAST MATERIAL IND
J 0
(-2410 3940);
DISPLAY 0.617021 (-2410 3940);
PAINT SKYBLUE (-2410 3940);
FORCEPROP 1 LAST PART_NUMBER E13358-018
J 0
(-2525 4000);
DISPLAY 0.617021 (-2525 4000);
PAINT BLUE (-2525 4000);
FORCEPROP 2 LAST CDS_LIB mstr_discrete
J 0
(-2550 3850);
PAINT MONO (-2550 3850);
DISPLAY INVISIBLE (-2550 3850);
FORCEPROP 2 LAST BOM_COST PVPP_KLM_VR
J 0
(-2550 3850);
PAINT WHITE (-2550 3850);
DISPLAY INVISIBLE (-2550 3850);
FORCEPROP 2 LAST ROOM PVPP_KLM_VR
J 2
(-2550 3850);
PAINT GREEN (-2550 3850);
DISPLAY INVISIBLE (-2550 3850);
FORCEPROP 0 LAST TOLERANCE 1%
J 0
(-2650 4000);
PAINT SKYBLUE (-2650 4000);
DISPLAY INVISIBLE (-2650 4000);
FORCEPROP 2 LAST REUSE_ID 30
J 0
(-2650 4050);
DISPLAY 1.042553 (-2650 4050);
PAINT ORANGE (-2650 4050);
DISPLAY INVISIBLE (-2650 4050);
FORCEPROP 2 LAST CDS_SEC 1
J 0
(-2650 4050);
DISPLAY 1.042553 (-2650 4050);
PAINT ORANGE (-2650 4050);
DISPLAY INVISIBLE (-2650 4050);
FORCEPROP 2 LAST $SEC 1
J 0
(-2650 4050);
DISPLAY 0.680851 (-2650 4050);
PAINT MONO (-2650 4050);
DISPLAY INVISIBLE (-2650 4050);
FORCEPROP 2 LAST CDS_LOCATION L7B1
J 0
(-2600 3900);
DISPLAY 0.617021 (-2600 3900);
PAINT AQUA (-2600 3900);
DISPLAY INVISIBLE (-2600 3900);
FORCEPROP 1 LAST PATH I239
J 0
(-2650 4000);
DISPLAY 0.978723 (-2650 4000);
PAINT ORANGE (-2650 4000);
DISPLAY INVISIBLE (-2650 4000);
FORCEADD CAP..2
R 2
(-3675 4200);
FORCEPROP 1 LAST LOCATION C7B30
J 1
(-3675 4300);
DISPLAY 0.617021 (-3675 4300);
PAINT AQUA (-3675 4300);
FORCEPROP 1 LAST PART_NUMBER 602433-020
J 1
(-3675 4250);
DISPLAY 0.617021 (-3675 4250);
PAINT BLUE (-3675 4250);
FORCEPROP 1 LASTPIN (-3775 4200) $PN 2
J 2
(-3760 4215);
DISPLAY 0.617021 (-3760 4215);
PAINT WHITE (-3760 4215);
FORCEPROP 1 LASTPIN (-3575 4200) $PN 1
J 2
(-3565 4215);
DISPLAY 0.617021 (-3565 4215);
PAINT WHITE (-3565 4215);
FORCEPROP 1 LAST PACK_TYPE 0603LF
J 1
(-3675 4000);
DISPLAY 0.617021 (-3675 4000);
PAINT SKYBLUE (-3675 4000);
FORCEPROP 1 LAST VOLTAGE 25V
J 2
(-3675 4100);
DISPLAY 0.617021 (-3675 4100);
PAINT SKYBLUE (-3675 4100);
FORCEPROP 1 LAST VALUE 0.1UF
J 0
(-3675 4100);
DISPLAY 0.617021 (-3675 4100);
PAINT SKYBLUE (-3675 4100);
FORCEPROP 1 LAST TOLERANCE 10%
J 0
(-3675 4050);
DISPLAY 0.617021 (-3675 4050);
PAINT SKYBLUE (-3675 4050);
FORCEPROP 1 LAST MATERIAL X7R
J 2
(-3675 4050);
DISPLAY 0.617021 (-3675 4050);
PAINT SKYBLUE (-3675 4050);
FORCEPROP 2 LAST CDS_LIB mstr_discrete
J 0
(-3675 4200);
PAINT MONO (-3675 4200);
DISPLAY INVISIBLE (-3675 4200);
FORCEPROP 2 LAST ROOM PVPP_KLM_VR
J 2
(-3675 4325);
DISPLAY 0.765957 (-3675 4325);
PAINT GREEN (-3675 4325);
DISPLAY INVISIBLE (-3675 4325);
FORCEPROP 2 LAST REUSE_ID 27
J 0
(-3675 4450);
DISPLAY 1.042553 (-3675 4450);
PAINT ORANGE (-3675 4450);
DISPLAY INVISIBLE (-3675 4450);
FORCEPROP 0 LAST SPOF TRUE
J 0
(-3675 4400);
DISPLAY 1.021277 (-3675 4400);
PAINT ORANGE (-3675 4400);
DISPLAY INVISIBLE (-3675 4400);
FORCEPROP 2 LAST CDS_SEC 1
J 0
(-3720 4410);
DISPLAY 1.042553 (-3720 4410);
PAINT ORANGE (-3720 4410);
DISPLAY INVISIBLE (-3720 4410);
FORCEPROP 2 LAST $SEC 1
J 0
(-3675 4450);
DISPLAY 0.680851 (-3675 4450);
PAINT MONO (-3675 4450);
DISPLAY INVISIBLE (-3675 4450);
FORCEPROP 2 LAST BOM_COST PVPP_KLM_VR
J 0
(-3720 4360);
DISPLAY 1.042553 (-3720 4360);
PAINT WHITE (-3720 4360);
DISPLAY INVISIBLE (-3720 4360);
FORCEPROP 1 LAST PATH I241
J 2
(-3675 4400);
DISPLAY 0.978723 (-3675 4400);
PAINT WHITE (-3675 4400);
DISPLAY INVISIBLE (-3675 4400);
FORCEADD AGND_SCSI..1
(-6125 2025);
FORCEPROP 3 LASTPIN (-6125 2075) SIG_NAME AGND_PVPP_DEF\g
J 0
(-6115 2085);
DISPLAY 0.659574 (-6115 2085);
PAINT MONO (-6115 2085);
DISPLAY INVISIBLE (-6115 2085);
FORCEPROP 1 LAST HDL_POWER AGND_PVPP_DEF
J 1
(-6050 1950);
DISPLAY 0.617021 (-6050 1950);
PAINT GREEN (-6050 1950);
FORCEPROP 2 LAST CDS_LIB mstr_symbols
J 0
(-6125 2025);
PAINT MONO (-6125 2025);
DISPLAY INVISIBLE (-6125 2025);
FORCEPROP 1 LAST PATH I247
J 0
(-6050 2025);
DISPLAY 0.872340 (-6050 2025);
PAINT AQUA (-6050 2025);
DISPLAY INVISIBLE (-6050 2025);
FORCEPROP 1 LAST VOLTAGE 0.0V
J 0
(-6170 1982);
DISPLAY 0.340426 (-6170 1982);
PAINT SKYBLUE (-6170 1982);
DISPLAY INVISIBLE (-6170 1982);
FORCEPROP 2 LAST BOM_COST PVPP_KLM_VR
J 0
(-6275 1975);
DISPLAY 1.042553 (-6275 1975);
PAINT WHITE (-6275 1975);
DISPLAY INVISIBLE (-6275 1975);
FORCEPROP 2 LAST ROOM PVPP_KLM_VR
J 0
(-6275 1975);
DISPLAY 1.042553 (-6275 1975);
PAINT GREEN (-6275 1975);
DISPLAY INVISIBLE (-6275 1975);
FORCEPROP 1 LAST BODY_TYPE PLUMBING
J 0
(-6170 1982);
DISPLAY 0.340426 (-6170 1982);
PAINT GREEN (-6170 1982);
DISPLAY INVISIBLE (-6170 1982);
FORCEADD AGND_SCSI..1
(-5425 1950);
FORCEPROP 3 LASTPIN (-5425 2000) SIG_NAME AGND_PVPP_DEF\g
J 0
(-5415 2010);
DISPLAY 0.659574 (-5415 2010);
PAINT MONO (-5415 2010);
DISPLAY INVISIBLE (-5415 2010);
FORCEPROP 1 LAST HDL_POWER AGND_PVPP_DEF
J 1
(-5350 1875);
DISPLAY 0.617021 (-5350 1875);
PAINT GREEN (-5350 1875);
FORCEPROP 1 LAST PATH I248
J 0
(-5350 1950);
DISPLAY 0.872340 (-5350 1950);
PAINT AQUA (-5350 1950);
DISPLAY INVISIBLE (-5350 1950);
FORCEPROP 2 LAST BOM_COST PVPP_KLM_VR
J 0
(-5575 1900);
DISPLAY 1.042553 (-5575 1900);
PAINT WHITE (-5575 1900);
DISPLAY INVISIBLE (-5575 1900);
FORCEPROP 1 LAST VOLTAGE 0.0V
J 0
(-5470 1907);
DISPLAY 0.340426 (-5470 1907);
PAINT SKYBLUE (-5470 1907);
DISPLAY INVISIBLE (-5470 1907);
FORCEPROP 2 LAST CDS_LIB mstr_symbols
J 0
(-5425 1950);
PAINT MONO (-5425 1950);
DISPLAY INVISIBLE (-5425 1950);
FORCEPROP 2 LAST ROOM PVPP_KLM_VR
J 0
(-5575 1900);
DISPLAY 1.042553 (-5575 1900);
PAINT GREEN (-5575 1900);
DISPLAY INVISIBLE (-5575 1900);
FORCEPROP 1 LAST BODY_TYPE PLUMBING
J 0
(-5470 1907);
DISPLAY 0.340426 (-5470 1907);
PAINT GREEN (-5470 1907);
DISPLAY INVISIBLE (-5470 1907);
FORCEADD AGND_SCSI..1
(-4725 1850);
FORCEPROP 3 LASTPIN (-4725 1900) SIG_NAME AGND_PVPP_DEF\g
J 0
(-4715 1910);
DISPLAY 0.659574 (-4715 1910);
PAINT MONO (-4715 1910);
DISPLAY INVISIBLE (-4715 1910);
FORCEPROP 1 LAST HDL_POWER AGND_PVPP_DEF
J 1
(-4650 1775);
DISPLAY 0.617021 (-4650 1775);
PAINT GREEN (-4650 1775);
FORCEPROP 2 LAST CDS_LIB mstr_symbols
J 0
(-4725 1850);
PAINT MONO (-4725 1850);
DISPLAY INVISIBLE (-4725 1850);
FORCEPROP 1 LAST PATH I249
J 0
(-4650 1850);
DISPLAY 0.872340 (-4650 1850);
PAINT AQUA (-4650 1850);
DISPLAY INVISIBLE (-4650 1850);
FORCEPROP 1 LAST VOLTAGE 0.0V
J 0
(-4770 1807);
DISPLAY 0.340426 (-4770 1807);
PAINT SKYBLUE (-4770 1807);
DISPLAY INVISIBLE (-4770 1807);
FORCEPROP 2 LAST ROOM PVPP_KLM_VR
J 0
(-4875 1800);
DISPLAY 1.042553 (-4875 1800);
PAINT GREEN (-4875 1800);
DISPLAY INVISIBLE (-4875 1800);
FORCEPROP 2 LAST BOM_COST PVPP_KLM_VR
J 0
(-4875 1800);
DISPLAY 1.042553 (-4875 1800);
PAINT WHITE (-4875 1800);
DISPLAY INVISIBLE (-4875 1800);
FORCEPROP 1 LAST BODY_TYPE PLUMBING
J 0
(-4770 1807);
DISPLAY 0.340426 (-4770 1807);
PAINT GREEN (-4770 1807);
DISPLAY INVISIBLE (-4770 1807);
FORCEADD AGND_SCSI..1
(-5100 1350);
FORCEPROP 3 LASTPIN (-5100 1400) SIG_NAME AGND_PVPP_DEF\g
J 0
(-5090 1410);
DISPLAY 0.659574 (-5090 1410);
PAINT MONO (-5090 1410);
DISPLAY INVISIBLE (-5090 1410);
FORCEPROP 1 LAST HDL_POWER AGND_PVPP_DEF
J 1
(-5100 1275);
DISPLAY 0.617021 (-5100 1275);
PAINT GREEN (-5100 1275);
FORCEPROP 1 LAST VOLTAGE 0
J 0
(-5025 1375);
DISPLAY 1.021277 (-5025 1375);
PAINT SKYBLUE (-5025 1375);
DISPLAY INVISIBLE (-5025 1375);
FORCEPROP 2 LAST CDS_LIB mstr_symbols
J 0
(-5100 1350);
PAINT MONO (-5100 1350);
DISPLAY INVISIBLE (-5100 1350);
FORCEPROP 1 LAST PATH I250
J 0
(-5025 1350);
DISPLAY 0.872340 (-5025 1350);
PAINT AQUA (-5025 1350);
DISPLAY INVISIBLE (-5025 1350);
FORCEPROP 1 LAST BODY_TYPE PLUMBING
J 0
(-5145 1307);
DISPLAY 0.340426 (-5145 1307);
PAINT GREEN (-5145 1307);
DISPLAY INVISIBLE (-5145 1307);
FORCEADD AGND_SCSI..1
(-6825 2125);
FORCEPROP 3 LASTPIN (-6825 2175) SIG_NAME AGND_PVPP_DEF\g
J 0
(-6815 2185);
DISPLAY 0.659574 (-6815 2185);
PAINT MONO (-6815 2185);
DISPLAY INVISIBLE (-6815 2185);
FORCEPROP 1 LAST HDL_POWER AGND_PVPP_DEF
J 1
(-6750 2050);
DISPLAY 0.617021 (-6750 2050);
PAINT GREEN (-6750 2050);
FORCEPROP 1 LAST VOLTAGE 0.0V
J 0
(-6870 2082);
DISPLAY 0.340426 (-6870 2082);
PAINT SKYBLUE (-6870 2082);
DISPLAY INVISIBLE (-6870 2082);
FORCEPROP 2 LAST CDS_LIB mstr_symbols
J 0
(-6825 2125);
PAINT MONO (-6825 2125);
DISPLAY INVISIBLE (-6825 2125);
FORCEPROP 1 LAST PATH I251
J 0
(-6750 2125);
DISPLAY 0.872340 (-6750 2125);
PAINT AQUA (-6750 2125);
DISPLAY INVISIBLE (-6750 2125);
FORCEPROP 2 LAST BOM_COST PVPP_KLM_VR
J 0
(-6975 2075);
DISPLAY 1.042553 (-6975 2075);
PAINT WHITE (-6975 2075);
DISPLAY INVISIBLE (-6975 2075);
FORCEPROP 2 LAST ROOM PVPP_KLM_VR
J 0
(-6975 2075);
DISPLAY 1.042553 (-6975 2075);
PAINT GREEN (-6975 2075);
DISPLAY INVISIBLE (-6975 2075);
FORCEPROP 1 LAST BODY_TYPE PLUMBING
J 0
(-6870 2082);
DISPLAY 0.340426 (-6870 2082);
PAINT GREEN (-6870 2082);
DISPLAY INVISIBLE (-6870 2082);
FORCEADD CAP_A..1
(-5475 3525);
FORCEPROP 1 LAST PACK_TYPE 0402V
J 0
(-5425 3325);
DISPLAY 0.617021 (-5425 3325);
PAINT SKYBLUE (-5425 3325);
FORCEPROP 1 LAST PART_NUMBER A36096-030
J 0
(-5425 3375);
DISPLAY 0.617021 (-5425 3375);
PAINT BLUE (-5425 3375);
FORCEPROP 1 LAST TOLERANCE 10%
J 0
(-5425 3475);
DISPLAY 0.617021 (-5425 3475);
PAINT SKYBLUE (-5425 3475);
FORCEPROP 1 LAST MATERIAL X7R
J 0
(-5425 3425);
DISPLAY 0.617021 (-5425 3425);
PAINT SKYBLUE (-5425 3425);
FORCEPROP 1 LAST LOCATION C7B6
J 0
(-5425 3625);
DISPLAY 0.617021 (-5425 3625);
PAINT AQUA (-5425 3625);
FORCEPROP 1 LASTPIN (-5475 3625) $PN 1
J 0
(-5465 3605);
DISPLAY 0.617021 (-5465 3605);
PAINT ORANGE (-5465 3605);
FORCEPROP 1 LAST VALUE 0.1UF
J 0
(-5425 3575);
DISPLAY 0.617021 (-5425 3575);
PAINT SKYBLUE (-5425 3575);
FORCEPROP 1 LAST VOLTAGE 16V
J 0
(-5425 3525);
DISPLAY 0.617021 (-5425 3525);
PAINT SKYBLUE (-5425 3525);
FORCEPROP 1 LASTPIN (-5475 3425) $PN 2
J 0
(-5465 3405);
DISPLAY 0.617021 (-5465 3405);
PAINT ORANGE (-5465 3405);
FORCEPROP 2 LAST SEC 1
J 0
(-5425 3725);
DISPLAY 0.680851 (-5425 3725);
PAINT MONO (-5425 3725);
DISPLAY INVISIBLE (-5425 3725);
FORCEPROP 2 LAST SEC_TYPE 0402V
J 0
(-5425 3725);
DISPLAY 1.021277 (-5425 3725);
PAINT ORANGE (-5425 3725);
DISPLAY INVISIBLE (-5425 3725);
FORCEPROP 2 LAST CDS_SEC 1
J 0
(-5425 3675);
PAINT ORANGE (-5425 3675);
DISPLAY INVISIBLE (-5425 3675);
FORCEPROP 2 LAST CDS_LOCATION C7B6
J 0
(-5425 3625);
DISPLAY 0.617021 (-5425 3625);
PAINT AQUA (-5425 3625);
DISPLAY INVISIBLE (-5425 3625);
FORCEPROP 1 LAST PATH I252
J 0
(-5425 3675);
DISPLAY 0.978723 (-5425 3675);
PAINT WHITE (-5425 3675);
DISPLAY INVISIBLE (-5425 3675);
FORCEPROP 2 LAST CDS_LIB dev_discrete
J 0
(-5475 3525);
PAINT ORANGE (-5475 3525);
DISPLAY INVISIBLE (-5475 3525);
FORCEADD CAP..1
(-6125 2425);
FORCEPROP 1 LAST PART_NUMBER E15431-003
J 0
(-6100 2275);
DISPLAY 0.617021 (-6100 2275);
PAINT BLUE (-6100 2275);
FORCEPROP 1 LAST PACK_TYPE 0603
J 0
(-6075 2325);
DISPLAY 0.617021 (-6075 2325);
PAINT SKYBLUE (-6075 2325);
FORCEPROP 1 LAST MATERIAL X6S
J 0
(-6075 2225);
DISPLAY 0.617021 (-6075 2225);
PAINT SKYBLUE (-6075 2225);
FORCEPROP 1 LAST TOLERANCE 10%
J 0
(-6050 2375);
DISPLAY 0.617021 (-6050 2375);
PAINT SKYBLUE (-6050 2375);
FORCEPROP 1 LAST VOLTAGE 6.3V
J 0
(-6050 2425);
DISPLAY 0.617021 (-6050 2425);
PAINT SKYBLUE (-6050 2425);
FORCEPROP 1 LAST LOCATION C3M10
J 0
(-6075 2525);
DISPLAY 0.617021 (-6075 2525);
PAINT AQUA (-6075 2525);
FORCEPROP 1 LASTPIN (-6125 2325) $PN 2
J 0
(-6115 2305);
DISPLAY 0.617021 (-6115 2305);
PAINT ORANGE (-6115 2305);
FORCEPROP 1 LASTPIN (-6125 2525) $PN 1
J 0
(-6115 2505);
DISPLAY 0.617021 (-6115 2505);
PAINT ORANGE (-6115 2505);
FORCEPROP 0 LAST CONFIG 078.47521.08BD
J 0
(-6300 2175);
DISPLAY 0.638298 (-6300 2175);
PAINT BROWN (-6300 2175);
DISPLAY BOTH (-6300 2175);
FORCEPROP 1 LAST VALUE 4.7UF
J 0
(-6075 2475);
DISPLAY 0.617021 (-6075 2475);
PAINT SKYBLUE (-6075 2475);
FORCEPROP 2 LAST REUSE_ID 26
J 0
(-6075 2625);
DISPLAY 1.042553 (-6075 2625);
PAINT ORANGE (-6075 2625);
DISPLAY INVISIBLE (-6075 2625);
FORCEPROP 2 LAST SEC_TYPE 0603
J 0
(-6075 2625);
DISPLAY 1.021277 (-6075 2625);
PAINT ORANGE (-6075 2625);
DISPLAY INVISIBLE (-6075 2625);
FORCEPROP 2 LAST BOM_COST PVPP_KLM_VR
J 0
(-6075 2575);
DISPLAY 1.042553 (-6075 2575);
PAINT WHITE (-6075 2575);
DISPLAY INVISIBLE (-6075 2575);
FORCEPROP 2 LAST SEC 1
J 0
(-6075 2625);
DISPLAY 0.680851 (-6075 2625);
PAINT MONO (-6075 2625);
DISPLAY INVISIBLE (-6075 2625);
FORCEPROP 1 LAST PATH I253
J 0
(-6075 2575);
DISPLAY 0.978723 (-6075 2575);
PAINT WHITE (-6075 2575);
DISPLAY INVISIBLE (-6075 2575);
FORCEPROP 2 LAST ROOM PVPP_KLM_VR
J 0
(-6075 2550);
PAINT GREEN (-6075 2550);
DISPLAY INVISIBLE (-6075 2550);
FORCEPROP 2 LAST CDS_LIB mstr_discrete
J 0
(-6125 2425);
PAINT MONO (-6125 2425);
DISPLAY INVISIBLE (-6125 2425);
FORCEPROP 2 LAST CDS_LOCATION C3M10
J 0
(-6075 2525);
DISPLAY 0.617021 (-6075 2525);
PAINT AQUA (-6075 2525);
DISPLAY INVISIBLE (-6075 2525);
FORCEADD AGND_SCSI..1
(-5775 2725);
FORCEPROP 3 LASTPIN (-5775 2775) SIG_NAME AGND_PVPP_DEF\g
J 0
(-5765 2785);
DISPLAY 0.659574 (-5765 2785);
PAINT MONO (-5765 2785);
DISPLAY INVISIBLE (-5765 2785);
FORCEPROP 1 LAST HDL_POWER AGND_PVPP_DEF
J 1
(-5700 2650);
DISPLAY 0.617021 (-5700 2650);
PAINT GREEN (-5700 2650);
FORCEPROP 1 LAST PATH I254
J 0
(-5700 2725);
DISPLAY 0.872340 (-5700 2725);
PAINT AQUA (-5700 2725);
DISPLAY INVISIBLE (-5700 2725);
FORCEPROP 2 LAST CDS_LIB mstr_symbols
J 0
(-5775 2725);
PAINT MONO (-5775 2725);
DISPLAY INVISIBLE (-5775 2725);
FORCEPROP 1 LAST VOLTAGE 0.0V
J 0
(-5820 2682);
DISPLAY 0.340426 (-5820 2682);
PAINT SKYBLUE (-5820 2682);
DISPLAY INVISIBLE (-5820 2682);
FORCEPROP 2 LAST ROOM PVPP_KLM_VR
J 0
(-5925 2675);
DISPLAY 1.042553 (-5925 2675);
PAINT GREEN (-5925 2675);
DISPLAY INVISIBLE (-5925 2675);
FORCEPROP 2 LAST BOM_COST PVPP_KLM_VR
J 0
(-5925 2675);
DISPLAY 1.042553 (-5925 2675);
PAINT WHITE (-5925 2675);
DISPLAY INVISIBLE (-5925 2675);
FORCEPROP 1 LAST BODY_TYPE PLUMBING
J 0
(-5820 2682);
DISPLAY 0.340426 (-5820 2682);
PAINT GREEN (-5820 2682);
DISPLAY INVISIBLE (-5820 2682);
FORCEADD GND..1
(-5475 3275);
FORCEPROP 3 LASTPIN (-5475 3325) SIG_NAME GND\g
J 0
(-5465 3335);
DISPLAY 0.659574 (-5465 3335);
PAINT MONO (-5465 3335);
DISPLAY INVISIBLE (-5465 3335);
FORCEPROP 1 LAST VOLTAGE 0
J 0
(-5475 3275);
PAINT SKYBLUE (-5475 3275);
DISPLAY INVISIBLE (-5475 3275);
FORCEPROP 2 LAST CDS_LIB mstr_symbols
J 0
(-5475 3275);
PAINT MONO (-5475 3275);
DISPLAY INVISIBLE (-5475 3275);
FORCEPROP 1 LAST SIZE 1B
J 0
(-5400 3225);
DISPLAY 0.872340 (-5400 3225);
PAINT GREEN (-5400 3225);
DISPLAY INVISIBLE (-5400 3225);
FORCEPROP 1 LAST PATH I255
J 0
(-5400 3275);
DISPLAY 0.872340 (-5400 3275);
PAINT AQUA (-5400 3275);
DISPLAY INVISIBLE (-5400 3275);
FORCEPROP 2 LAST ROOM PVPP_KLM_VR
J 0
(-6050 3350);
DISPLAY 1.042553 (-6050 3350);
PAINT GREEN (-6050 3350);
DISPLAY INVISIBLE (-6050 3350);
FORCEPROP 2 LAST BOM_COST PVPP_KLM_VR
J 0
(-6325 3350);
DISPLAY 1.042553 (-6325 3350);
PAINT WHITE (-6325 3350);
DISPLAY INVISIBLE (-6325 3350);
FORCEPROP 1 LAST BODY_TYPE PLUMBING
J 0
(-5520 3232);
DISPLAY 0.340426 (-5520 3232);
PAINT GREEN (-5520 3232);
DISPLAY INVISIBLE (-5520 3232);
FORCEPROP 1 LAST HDL_POWER GND
J 0
(-5475 3425);
DISPLAY 0.872340 (-5475 3425);
PAINT GREEN (-5475 3425);
DISPLAY INVISIBLE (-5475 3425);
FORCEADD RES..1
(-3650 975);
FORCEPROP 1 LAST PART_NUMBER G21796-250
J 0
(-3700 1075);
DISPLAY 0.617021 (-3700 1075);
PAINT BLUE (-3700 1075);
FORCEPROP 1 LASTPIN (-3750 975) $PN 1
J 0
(-3738 987);
DISPLAY 0.617021 (-3738 987);
PAINT ORANGE (-3738 987);
FORCEPROP 1 LAST VALUE 22.1
J 2
(-3675 875);
DISPLAY 0.617021 (-3675 875);
PAINT SKYBLUE (-3675 875);
FORCEPROP 1 LAST LOCATION R7B12
J 0
(-3700 1025);
DISPLAY 0.617021 (-3700 1025);
PAINT AQUA (-3700 1025);
FORCEPROP 1 LASTPIN (-3550 975) $PN 2
J 0
(-3588 987);
DISPLAY 0.617021 (-3588 987);
PAINT ORANGE (-3588 987);
FORCEPROP 1 LAST TOLERANCE 1.0%
J 0
(-3650 875);
DISPLAY 0.617021 (-3650 875);
PAINT SKYBLUE (-3650 875);
FORCEPROP 1 LAST PACK_TYPE 0402
J 0
(-3400 825);
DISPLAY 0.617021 (-3400 825);
PAINT SKYBLUE (-3400 825);
FORCEPROP 1 LAST MATERIAL CHIP
J 0
(-3650 825);
DISPLAY 0.617021 (-3650 825);
PAINT SKYBLUE (-3650 825);
FORCEPROP 1 LAST WATTAGE 1/16W
J 2
(-3675 825);
DISPLAY 0.617021 (-3675 825);
PAINT SKYBLUE (-3675 825);
FORCEPROP 2 LAST ROOM PVPP_DEF_VR
J 0
(-3700 1075);
DISPLAY 1.361702 (-3700 1075);
PAINT ORANGE (-3700 1075);
DISPLAY INVISIBLE (-3700 1075);
FORCEPROP 1 LAST PATH I257
J 0
(-3700 1125);
DISPLAY 0.978723 (-3700 1125);
PAINT WHITE (-3700 1125);
DISPLAY INVISIBLE (-3700 1125);
FORCEPROP 2 LAST CDS_LOCATION R7B12
J 0
(-3700 1025);
DISPLAY 0.617021 (-3700 1025);
PAINT AQUA (-3700 1025);
DISPLAY INVISIBLE (-3700 1025);
FORCEPROP 2 LAST SEC 1
J 0
(-3700 1175);
DISPLAY 0.680851 (-3700 1175);
PAINT MONO (-3700 1175);
DISPLAY INVISIBLE (-3700 1175);
FORCEPROP 2 LAST SEC_TYPE 0402
J 0
(-3700 1175);
DISPLAY 1.021277 (-3700 1175);
PAINT ORANGE (-3700 1175);
DISPLAY INVISIBLE (-3700 1175);
FORCEPROP 2 LAST CDS_LIB mstr_discrete
J 0
(-3650 975);
PAINT MONO (-3650 975);
DISPLAY INVISIBLE (-3650 975);
FORCEADD CAP..1
(-6950 4100);
FORCEPROP 1 LAST VOLTAGE 16V
J 0
(-6900 4100);
DISPLAY 0.617021 (-6900 4100);
PAINT SKYBLUE (-6900 4100);
FORCEPROP 1 LAST TOLERANCE 10%
J 0
(-6900 4050);
DISPLAY 0.617021 (-6900 4050);
PAINT SKYBLUE (-6900 4050);
FORCEPROP 1 LASTPIN (-6950 4000) $PN 2
J 0
(-6940 3980);
DISPLAY 0.617021 (-6940 3980);
PAINT ORANGE (-6940 3980);
FORCEPROP 1 LAST MATERIAL X6S
J 0
(-6900 4000);
DISPLAY 0.617021 (-6900 4000);
PAINT SKYBLUE (-6900 4000);
FORCEPROP 1 LAST PACK_TYPE 0805
J 0
(-6900 3900);
DISPLAY 0.617021 (-6900 3900);
PAINT SKYBLUE (-6900 3900);
FORCEPROP 1 LAST PART_NUMBER C95333-007
J 0
(-6900 3950);
DISPLAY 0.617021 (-6900 3950);
PAINT BLUE (-6900 3950);
FORCEPROP 1 LAST VALUE 10UF
J 0
(-6900 4150);
DISPLAY 0.617021 (-6900 4150);
PAINT SKYBLUE (-6900 4150);
FORCEPROP 1 LASTPIN (-6950 4200) $PN 1
J 0
(-6940 4180);
DISPLAY 0.617021 (-6940 4180);
PAINT ORANGE (-6940 4180);
FORCEPROP 1 LAST LOCATION C3M8
J 0
(-6900 4200);
DISPLAY 0.617021 (-6900 4200);
PAINT AQUA (-6900 4200);
FORCEPROP 2 LAST CDS_LIB mstr_discrete
J 0
(-6950 4100);
PAINT MONO (-6950 4100);
DISPLAY INVISIBLE (-6950 4100);
FORCEPROP 2 LAST CDS_LOCATION C3M8
J 0
(-6900 4200);
DISPLAY 0.617021 (-6900 4200);
PAINT AQUA (-6900 4200);
DISPLAY INVISIBLE (-6900 4200);
FORCEPROP 2 LAST SEC_TYPE 0805
J 0
(-6900 4300);
DISPLAY 1.021277 (-6900 4300);
PAINT ORANGE (-6900 4300);
DISPLAY INVISIBLE (-6900 4300);
FORCEPROP 2 LAST SEC 1
J 0
(-6900 4300);
DISPLAY 0.680851 (-6900 4300);
PAINT MONO (-6900 4300);
DISPLAY INVISIBLE (-6900 4300);
FORCEPROP 1 LAST PATH I259
J 0
(-6900 4250);
DISPLAY 0.978723 (-6900 4250);
PAINT WHITE (-6900 4250);
DISPLAY INVISIBLE (-6900 4250);
FORCEADD CAP..1
(-6600 4100);
FORCEPROP 1 LAST TOLERANCE 10%
J 0
(-6550 4050);
DISPLAY 0.617021 (-6550 4050);
PAINT SKYBLUE (-6550 4050);
FORCEPROP 1 LAST LOCATION C3M15
J 0
(-6550 4200);
DISPLAY 0.617021 (-6550 4200);
PAINT AQUA (-6550 4200);
FORCEPROP 1 LAST VALUE 10UF
J 0
(-6550 4150);
DISPLAY 0.617021 (-6550 4150);
PAINT SKYBLUE (-6550 4150);
FORCEPROP 1 LAST VOLTAGE 16V
J 0
(-6550 4100);
DISPLAY 0.617021 (-6550 4100);
PAINT SKYBLUE (-6550 4100);
FORCEPROP 1 LASTPIN (-6600 4200) $PN 1
J 0
(-6590 4180);
DISPLAY 0.617021 (-6590 4180);
PAINT ORANGE (-6590 4180);
FORCEPROP 1 LASTPIN (-6600 4000) $PN 2
J 0
(-6590 3980);
DISPLAY 0.617021 (-6590 3980);
PAINT ORANGE (-6590 3980);
FORCEPROP 1 LAST PACK_TYPE 0805
J 0
(-6550 3900);
DISPLAY 0.617021 (-6550 3900);
PAINT SKYBLUE (-6550 3900);
FORCEPROP 1 LAST MATERIAL X6S
J 0
(-6550 4000);
DISPLAY 0.617021 (-6550 4000);
PAINT SKYBLUE (-6550 4000);
FORCEPROP 1 LAST PART_NUMBER C95333-007
J 0
(-6550 3950);
DISPLAY 0.617021 (-6550 3950);
PAINT BLUE (-6550 3950);
FORCEPROP 1 LAST PATH I260
J 0
(-6550 4250);
DISPLAY 0.978723 (-6550 4250);
PAINT WHITE (-6550 4250);
DISPLAY INVISIBLE (-6550 4250);
FORCEPROP 2 LAST SEC 1
J 0
(-6550 4300);
DISPLAY 0.680851 (-6550 4300);
PAINT MONO (-6550 4300);
DISPLAY INVISIBLE (-6550 4300);
FORCEPROP 2 LAST SEC_TYPE 0805
J 0
(-6550 4300);
DISPLAY 1.021277 (-6550 4300);
PAINT ORANGE (-6550 4300);
DISPLAY INVISIBLE (-6550 4300);
FORCEPROP 2 LAST CDS_LOCATION C3M15
J 0
(-6550 4200);
DISPLAY 0.617021 (-6550 4200);
PAINT AQUA (-6550 4200);
DISPLAY INVISIBLE (-6550 4200);
FORCEPROP 2 LAST CDS_LIB mstr_discrete
J 0
(-6600 4100);
PAINT MONO (-6600 4100);
DISPLAY INVISIBLE (-6600 4100);
FORCEADD CAP..1
(-6225 4100);
FORCEPROP 1 LASTPIN (-6225 4000) $PN 2
J 0
(-6215 3980);
DISPLAY 0.617021 (-6215 3980);
PAINT ORANGE (-6215 3980);
FORCEPROP 1 LAST MATERIAL X6S
J 0
(-6175 4000);
DISPLAY 0.617021 (-6175 4000);
PAINT SKYBLUE (-6175 4000);
FORCEPROP 1 LAST PART_NUMBER C95333-007
J 0
(-6175 3950);
DISPLAY 0.617021 (-6175 3950);
PAINT BLUE (-6175 3950);
FORCEPROP 1 LAST VALUE 10UF
J 0
(-6175 4150);
DISPLAY 0.617021 (-6175 4150);
PAINT SKYBLUE (-6175 4150);
FORCEPROP 1 LAST VOLTAGE 16V
J 0
(-6175 4100);
DISPLAY 0.617021 (-6175 4100);
PAINT SKYBLUE (-6175 4100);
FORCEPROP 1 LASTPIN (-6225 4200) $PN 1
J 0
(-6215 4180);
DISPLAY 0.617021 (-6215 4180);
PAINT ORANGE (-6215 4180);
FORCEPROP 1 LAST TOLERANCE 10%
J 0
(-6175 4050);
DISPLAY 0.617021 (-6175 4050);
PAINT SKYBLUE (-6175 4050);
FORCEPROP 1 LAST PACK_TYPE 0805
J 0
(-6175 3900);
DISPLAY 0.617021 (-6175 3900);
PAINT SKYBLUE (-6175 3900);
FORCEPROP 1 LAST LOCATION C3M16
J 0
(-6175 4200);
DISPLAY 0.617021 (-6175 4200);
PAINT AQUA (-6175 4200);
FORCEPROP 1 LAST PATH I261
J 0
(-6175 4250);
DISPLAY 0.978723 (-6175 4250);
PAINT WHITE (-6175 4250);
DISPLAY INVISIBLE (-6175 4250);
FORCEPROP 2 LAST SEC 1
J 0
(-6175 4300);
DISPLAY 0.680851 (-6175 4300);
PAINT MONO (-6175 4300);
DISPLAY INVISIBLE (-6175 4300);
FORCEPROP 2 LAST SEC_TYPE 0805
J 0
(-6175 4300);
DISPLAY 1.021277 (-6175 4300);
PAINT ORANGE (-6175 4300);
DISPLAY INVISIBLE (-6175 4300);
FORCEPROP 2 LAST CDS_LOCATION C3M16
J 0
(-6175 4200);
DISPLAY 0.617021 (-6175 4200);
PAINT AQUA (-6175 4200);
DISPLAY INVISIBLE (-6175 4200);
FORCEPROP 2 LAST CDS_LIB mstr_discrete
J 0
(-6225 4100);
PAINT MONO (-6225 4100);
DISPLAY INVISIBLE (-6225 4100);
FORCEADD CAP..1
(-5850 4100);
FORCEPROP 1 LAST PART_NUMBER C95333-007
J 0
(-5800 3950);
DISPLAY 0.617021 (-5800 3950);
PAINT BLUE (-5800 3950);
FORCEPROP 1 LAST LOCATION C7B5
J 0
(-5800 4200);
DISPLAY 0.617021 (-5800 4200);
PAINT AQUA (-5800 4200);
FORCEPROP 1 LAST VALUE 10UF
J 0
(-5800 4150);
DISPLAY 0.617021 (-5800 4150);
PAINT SKYBLUE (-5800 4150);
FORCEPROP 1 LAST VOLTAGE 16V
J 0
(-5800 4100);
DISPLAY 0.617021 (-5800 4100);
PAINT SKYBLUE (-5800 4100);
FORCEPROP 1 LASTPIN (-5850 4200) $PN 1
J 0
(-5840 4180);
DISPLAY 0.617021 (-5840 4180);
PAINT ORANGE (-5840 4180);
FORCEPROP 1 LAST TOLERANCE 10%
J 0
(-5800 4050);
DISPLAY 0.617021 (-5800 4050);
PAINT SKYBLUE (-5800 4050);
FORCEPROP 1 LAST PACK_TYPE 0805
J 0
(-5800 3900);
DISPLAY 0.617021 (-5800 3900);
PAINT SKYBLUE (-5800 3900);
FORCEPROP 1 LAST MATERIAL X6S
J 0
(-5800 4000);
DISPLAY 0.617021 (-5800 4000);
PAINT SKYBLUE (-5800 4000);
FORCEPROP 1 LASTPIN (-5850 4000) $PN 2
J 0
(-5840 3980);
DISPLAY 0.617021 (-5840 3980);
PAINT ORANGE (-5840 3980);
FORCEPROP 1 LAST PATH I262
J 0
(-5800 4250);
DISPLAY 0.978723 (-5800 4250);
PAINT WHITE (-5800 4250);
DISPLAY INVISIBLE (-5800 4250);
FORCEPROP 2 LAST SEC 1
J 0
(-5800 4300);
DISPLAY 0.680851 (-5800 4300);
PAINT MONO (-5800 4300);
DISPLAY INVISIBLE (-5800 4300);
FORCEPROP 2 LAST SEC_TYPE 0805
J 0
(-5800 4300);
DISPLAY 1.021277 (-5800 4300);
PAINT ORANGE (-5800 4300);
DISPLAY INVISIBLE (-5800 4300);
FORCEPROP 2 LAST CDS_LOCATION C7B5
J 0
(-5800 4200);
DISPLAY 0.617021 (-5800 4200);
PAINT AQUA (-5800 4200);
DISPLAY INVISIBLE (-5800 4200);
FORCEPROP 2 LAST CDS_LIB mstr_discrete
J 0
(-5850 4100);
PAINT MONO (-5850 4100);
DISPLAY INVISIBLE (-5850 4100);
FORCEADD GND..1
(-6950 3900);
FORCEPROP 3 LASTPIN (-6950 3950) SIG_NAME GND\g
J 0
(-6940 3960);
DISPLAY 0.659574 (-6940 3960);
PAINT MONO (-6940 3960);
DISPLAY INVISIBLE (-6940 3960);
FORCEPROP 2 LAST BOM_COST PVPP_KLM_VR
J 0
(-7800 3975);
DISPLAY 1.042553 (-7800 3975);
PAINT WHITE (-7800 3975);
DISPLAY INVISIBLE (-7800 3975);
FORCEPROP 2 LAST ROOM PVPP_KLM_VR
J 0
(-7525 3975);
DISPLAY 1.042553 (-7525 3975);
PAINT GREEN (-7525 3975);
DISPLAY INVISIBLE (-7525 3975);
FORCEPROP 1 LAST VOLTAGE 0
J 0
(-6950 3900);
PAINT SKYBLUE (-6950 3900);
DISPLAY INVISIBLE (-6950 3900);
FORCEPROP 2 LAST CDS_LIB mstr_symbols
J 0
(-6950 3900);
PAINT MONO (-6950 3900);
DISPLAY INVISIBLE (-6950 3900);
FORCEPROP 1 LAST PATH I263
J 0
(-6875 3900);
DISPLAY 0.872340 (-6875 3900);
PAINT AQUA (-6875 3900);
DISPLAY INVISIBLE (-6875 3900);
FORCEPROP 1 LAST SIZE 1B
J 0
(-6875 3850);
DISPLAY 0.872340 (-6875 3850);
PAINT GREEN (-6875 3850);
DISPLAY INVISIBLE (-6875 3850);
FORCEPROP 1 LAST BODY_TYPE PLUMBING
J 0
(-6995 3857);
DISPLAY 0.340426 (-6995 3857);
PAINT GREEN (-6995 3857);
DISPLAY INVISIBLE (-6995 3857);
FORCEPROP 1 LAST HDL_POWER GND
J 0
(-6950 4050);
DISPLAY 0.872340 (-6950 4050);
PAINT GREEN (-6950 4050);
DISPLAY INVISIBLE (-6950 4050);
FORCEADD GND..1
(-6600 3900);
FORCEPROP 3 LASTPIN (-6600 3950) SIG_NAME GND\g
J 0
(-6590 3960);
DISPLAY 0.659574 (-6590 3960);
PAINT MONO (-6590 3960);
DISPLAY INVISIBLE (-6590 3960);
FORCEPROP 1 LAST SIZE 1B
J 0
(-6525 3850);
DISPLAY 0.872340 (-6525 3850);
PAINT GREEN (-6525 3850);
DISPLAY INVISIBLE (-6525 3850);
FORCEPROP 1 LAST PATH I264
J 0
(-6525 3900);
DISPLAY 0.872340 (-6525 3900);
PAINT AQUA (-6525 3900);
DISPLAY INVISIBLE (-6525 3900);
FORCEPROP 2 LAST CDS_LIB mstr_symbols
J 0
(-6600 3900);
PAINT MONO (-6600 3900);
DISPLAY INVISIBLE (-6600 3900);
FORCEPROP 1 LAST VOLTAGE 0
J 0
(-6600 3900);
PAINT SKYBLUE (-6600 3900);
DISPLAY INVISIBLE (-6600 3900);
FORCEPROP 2 LAST ROOM PVPP_KLM_VR
J 0
(-7175 3975);
DISPLAY 1.042553 (-7175 3975);
PAINT GREEN (-7175 3975);
DISPLAY INVISIBLE (-7175 3975);
FORCEPROP 2 LAST BOM_COST PVPP_KLM_VR
J 0
(-7450 3975);
DISPLAY 1.042553 (-7450 3975);
PAINT WHITE (-7450 3975);
DISPLAY INVISIBLE (-7450 3975);
FORCEPROP 1 LAST BODY_TYPE PLUMBING
J 0
(-6645 3857);
DISPLAY 0.340426 (-6645 3857);
PAINT GREEN (-6645 3857);
DISPLAY INVISIBLE (-6645 3857);
FORCEPROP 1 LAST HDL_POWER GND
J 0
(-6600 4050);
DISPLAY 0.872340 (-6600 4050);
PAINT GREEN (-6600 4050);
DISPLAY INVISIBLE (-6600 4050);
FORCEADD GND..1
(-6225 3900);
FORCEPROP 3 LASTPIN (-6225 3950) SIG_NAME GND\g
J 0
(-6215 3960);
DISPLAY 0.659574 (-6215 3960);
PAINT MONO (-6215 3960);
DISPLAY INVISIBLE (-6215 3960);
FORCEPROP 1 LAST PATH I265
J 0
(-6150 3900);
DISPLAY 0.872340 (-6150 3900);
PAINT AQUA (-6150 3900);
DISPLAY INVISIBLE (-6150 3900);
FORCEPROP 1 LAST SIZE 1B
J 0
(-6150 3850);
DISPLAY 0.872340 (-6150 3850);
PAINT GREEN (-6150 3850);
DISPLAY INVISIBLE (-6150 3850);
FORCEPROP 2 LAST CDS_LIB mstr_symbols
J 0
(-6225 3900);
PAINT MONO (-6225 3900);
DISPLAY INVISIBLE (-6225 3900);
FORCEPROP 1 LAST VOLTAGE 0
J 0
(-6225 3900);
PAINT SKYBLUE (-6225 3900);
DISPLAY INVISIBLE (-6225 3900);
FORCEPROP 2 LAST ROOM PVPP_KLM_VR
J 0
(-6800 3975);
DISPLAY 1.042553 (-6800 3975);
PAINT GREEN (-6800 3975);
DISPLAY INVISIBLE (-6800 3975);
FORCEPROP 2 LAST BOM_COST PVPP_KLM_VR
J 0
(-7075 3975);
DISPLAY 1.042553 (-7075 3975);
PAINT WHITE (-7075 3975);
DISPLAY INVISIBLE (-7075 3975);
FORCEPROP 1 LAST BODY_TYPE PLUMBING
J 0
(-6270 3857);
DISPLAY 0.340426 (-6270 3857);
PAINT GREEN (-6270 3857);
DISPLAY INVISIBLE (-6270 3857);
FORCEPROP 1 LAST HDL_POWER GND
J 0
(-6225 4050);
DISPLAY 0.872340 (-6225 4050);
PAINT GREEN (-6225 4050);
DISPLAY INVISIBLE (-6225 4050);
FORCEADD GND..1
(-5850 3900);
FORCEPROP 3 LASTPIN (-5850 3950) SIG_NAME GND\g
J 0
(-5840 3960);
DISPLAY 0.659574 (-5840 3960);
PAINT MONO (-5840 3960);
DISPLAY INVISIBLE (-5840 3960);
FORCEPROP 1 LAST PATH I266
J 0
(-5775 3900);
DISPLAY 0.872340 (-5775 3900);
PAINT AQUA (-5775 3900);
DISPLAY INVISIBLE (-5775 3900);
FORCEPROP 1 LAST SIZE 1B
J 0
(-5775 3850);
DISPLAY 0.872340 (-5775 3850);
PAINT GREEN (-5775 3850);
DISPLAY INVISIBLE (-5775 3850);
FORCEPROP 2 LAST CDS_LIB mstr_symbols
J 0
(-5850 3900);
PAINT MONO (-5850 3900);
DISPLAY INVISIBLE (-5850 3900);
FORCEPROP 1 LAST VOLTAGE 0
J 0
(-5850 3900);
PAINT SKYBLUE (-5850 3900);
DISPLAY INVISIBLE (-5850 3900);
FORCEPROP 2 LAST ROOM PVPP_KLM_VR
J 0
(-6425 3975);
DISPLAY 1.042553 (-6425 3975);
PAINT GREEN (-6425 3975);
DISPLAY INVISIBLE (-6425 3975);
FORCEPROP 2 LAST BOM_COST PVPP_KLM_VR
J 0
(-6700 3975);
DISPLAY 1.042553 (-6700 3975);
PAINT WHITE (-6700 3975);
DISPLAY INVISIBLE (-6700 3975);
FORCEPROP 1 LAST BODY_TYPE PLUMBING
J 0
(-5895 3857);
DISPLAY 0.340426 (-5895 3857);
PAINT GREEN (-5895 3857);
DISPLAY INVISIBLE (-5895 3857);
FORCEPROP 1 LAST HDL_POWER GND
J 0
(-5850 4050);
DISPLAY 0.872340 (-5850 4050);
PAINT GREEN (-5850 4050);
DISPLAY INVISIBLE (-5850 4050);
FORCEADD CAPP..1
(-1800 3650);
FORCEPROP 1 LAST VOLTAGE 4V
J 0
(-1750 3650);
DISPLAY 0.617021 (-1750 3650);
PAINT SKYBLUE (-1750 3650);
FORCEPROP 1 LAST VALUE 220UF
J 0
(-1750 3750);
DISPLAY 0.617021 (-1750 3750);
PAINT SKYBLUE (-1750 3750);
FORCEPROP 1 LAST LOCATION C4M1
J 0
(-1750 3800);
DISPLAY 0.617021 (-1750 3800);
PAINT AQUA (-1750 3800);
FORCEPROP 1 LASTPIN (-1800 3550) $PN 2
J 0
(-1790 3535);
DISPLAY 0.617021 (-1790 3535);
PAINT ORANGE (-1790 3535);
FORCEPROP 1 LASTPIN (-1800 3750) $PN 1
J 0
(-1790 3735);
DISPLAY 0.617021 (-1790 3735);
PAINT ORANGE (-1790 3735);
FORCEPROP 1 LAST TOLERANCE 20%
J 0
(-1750 3700);
DISPLAY 0.617021 (-1750 3700);
PAINT SKYBLUE (-1750 3700);
FORCEPROP 1 LAST MATERIAL POSCAP
J 0
(-1750 3600);
DISPLAY 0.617021 (-1750 3600);
PAINT SKYBLUE (-1750 3600);
FORCEPROP 1 LAST PACK_TYPE 7343
J 0
(-1750 3550);
DISPLAY 0.617021 (-1750 3550);
PAINT SKYBLUE (-1750 3550);
FORCEPROP 1 LAST PART_NUMBER 724613-067
J 0
(-1750 3500);
DISPLAY 0.617021 (-1750 3500);
PAINT BLUE (-1750 3500);
FORCEPROP 0 LAST GROUP PWR_BULK_CAP
J 0
(-1735 3401);
DISPLAY 0.638298 (-1735 3401);
PAINT BROWN (-1735 3401);
DISPLAY BOTH (-1735 3401);
FORCEPROP 2 LAST SEC_TYPE 7343
J 0
(-1750 3850);
DISPLAY 1.021277 (-1750 3850);
PAINT ORANGE (-1750 3850);
DISPLAY INVISIBLE (-1750 3850);
FORCEPROP 2 LAST SEC 1
J 0
(-1750 3850);
DISPLAY 0.680851 (-1750 3850);
PAINT MONO (-1750 3850);
DISPLAY INVISIBLE (-1750 3850);
FORCEPROP 2 LAST CDS_LOCATION C4M1
J 0
(-1750 3750);
DISPLAY 0.617021 (-1750 3750);
PAINT AQUA (-1750 3750);
DISPLAY INVISIBLE (-1750 3750);
FORCEPROP 1 LAST PATH I267
J 0
(-1750 3800);
DISPLAY 0.978723 (-1750 3800);
PAINT ORANGE (-1750 3800);
DISPLAY INVISIBLE (-1750 3800);
FORCEPROP 2 LAST CDS_LIB mstr_discrete
J 0
(-1800 3650);
PAINT ORANGE (-1800 3650);
DISPLAY INVISIBLE (-1800 3650);
FORCEADD RES..2
(-1350 2525);
FORCEPROP 1 LASTPIN (-1350 2425) $PN 2
J 0
(-1345 2435);
DISPLAY 0.617021 (-1345 2435);
PAINT ORANGE (-1345 2435);
FORCEPROP 1 LASTPIN (-1350 2625) $PN 1
J 0
(-1345 2587);
DISPLAY 0.617021 (-1345 2587);
PAINT ORANGE (-1345 2587);
FORCEPROP 1 LAST VALUE 1.0K
J 0
(-1305 2600);
DISPLAY 0.617021 (-1305 2600);
PAINT SKYBLUE (-1305 2600);
FORCEPROP 1 LAST LOCATION R7B18
J 0
(-1305 2650);
DISPLAY 0.617021 (-1305 2650);
PAINT AQUA (-1305 2650);
FORCEPROP 1 LAST TOLERANCE 0.1%
J 0
(-1305 2550);
DISPLAY 0.617021 (-1305 2550);
PAINT SKYBLUE (-1305 2550);
FORCEPROP 1 LAST WATTAGE 1/16W
J 0
(-1310 2500);
DISPLAY 0.617021 (-1310 2500);
PAINT SKYBLUE (-1310 2500);
FORCEPROP 1 LAST PACK_TYPE 0402
J 0
(-1310 2450);
DISPLAY 0.617021 (-1310 2450);
PAINT SKYBLUE (-1310 2450);
FORCEPROP 1 LAST MATERIAL CHIP
J 0
(-1310 2400);
DISPLAY 0.617021 (-1310 2400);
PAINT SKYBLUE (-1310 2400);
FORCEPROP 1 LAST PART_NUMBER G85996-004
J 0
(-1335 2350);
DISPLAY 0.617021 (-1335 2350);
PAINT BLUE (-1335 2350);
FORCEPROP 2 LAST CDS_LIB mstr_discrete
J 0
(-1350 2525);
PAINT MONO (-1350 2525);
DISPLAY INVISIBLE (-1350 2525);
FORCEPROP 2 LAST CDS_LOCATION R7B18
J 0
(-1305 2650);
DISPLAY 0.617021 (-1305 2650);
PAINT AQUA (-1305 2650);
DISPLAY INVISIBLE (-1305 2650);
FORCEPROP 2 LAST BOM_COST PVPP_KLM_VR
J 0
(-1305 2705);
DISPLAY 1.042553 (-1305 2705);
PAINT WHITE (-1305 2705);
DISPLAY INVISIBLE (-1305 2705);
FORCEPROP 1 LAST PATH I298
J 0
(-1300 2700);
DISPLAY 0.978723 (-1300 2700);
PAINT WHITE (-1300 2700);
DISPLAY INVISIBLE (-1300 2700);
FORCEPROP 2 LAST ROOM PVPP_KLM_VR
J 0
(-1305 2680);
PAINT GREEN (-1305 2680);
DISPLAY INVISIBLE (-1305 2680);
FORCEPROP 2 LAST SEC 1
J 0
(-1300 2750);
DISPLAY 0.680851 (-1300 2750);
PAINT MONO (-1300 2750);
DISPLAY INVISIBLE (-1300 2750);
FORCEPROP 2 LAST REUSE_ID 9
J 0
(-1300 2750);
DISPLAY 1.042553 (-1300 2750);
PAINT ORANGE (-1300 2750);
DISPLAY INVISIBLE (-1300 2750);
FORCEPROP 0 LAST SPOF TRUE
J 0
(-1300 2750);
DISPLAY 1.021277 (-1300 2750);
PAINT ORANGE (-1300 2750);
DISPLAY INVISIBLE (-1300 2750);
FORCEPROP 2 LAST SEC_TYPE 0402
J 0
(-1300 2750);
DISPLAY 1.021277 (-1300 2750);
PAINT ORANGE (-1300 2750);
DISPLAY INVISIBLE (-1300 2750);
FORCEADD RES..1
R 5
(-1700 2925);
FORCEPROP 1 LAST PART_NUMBER G21497-005
J 0
(-1675 2725);
DISPLAY 0.617021 (-1675 2725);
PAINT BLUE (-1675 2725);
FORCEPROP 1 LASTPIN (-1700 3025) $PN 1
J 0
(-1688 3013);
DISPLAY 0.617021 (-1688 3013);
PAINT ORANGE (-1688 3013);
FORCEPROP 1 LAST VALUE 0.0
J 0
(-1650 2975);
DISPLAY 0.617021 (-1650 2975);
PAINT SKYBLUE (-1650 2975);
FORCEPROP 1 LAST WATTAGE 1/16W
J 0
(-1675 2925);
DISPLAY 0.617021 (-1675 2925);
PAINT SKYBLUE (-1675 2925);
FORCEPROP 1 LAST TOLERANCE 5%
J 0
(-1650 2875);
DISPLAY 0.617021 (-1650 2875);
PAINT SKYBLUE (-1650 2875);
FORCEPROP 1 LAST PACK_TYPE 0402
J 0
(-1675 2775);
DISPLAY 0.617021 (-1675 2775);
PAINT SKYBLUE (-1675 2775);
FORCEPROP 1 LAST MATERIAL CHIP
J 0
(-1675 2825);
DISPLAY 0.617021 (-1675 2825);
PAINT SKYBLUE (-1675 2825);
FORCEPROP 1 LASTPIN (-1700 2825) $PN 2
J 0
(-1688 2863);
DISPLAY 0.617021 (-1688 2863);
PAINT ORANGE (-1688 2863);
FORCEPROP 1 LAST LOCATION R7B11
J 0
(-1550 2875);
DISPLAY 0.617021 (-1550 2875);
PAINT AQUA (-1550 2875);
FORCEPROP 2 LAST SEC 1
J 0
(-1625 3075);
DISPLAY 0.680851 (-1625 3075);
PAINT MONO (-1625 3075);
DISPLAY INVISIBLE (-1625 3075);
FORCEPROP 0 LAST SPOF TRUE
J 0
(-1650 3075);
DISPLAY 1.021277 (-1650 3075);
PAINT ORANGE (-1650 3075);
DISPLAY INVISIBLE (-1650 3075);
FORCEPROP 2 LAST SEC_TYPE 0402
J 0
(-1625 3075);
DISPLAY 1.021277 (-1625 3075);
PAINT ORANGE (-1625 3075);
DISPLAY INVISIBLE (-1625 3075);
FORCEPROP 1 LAST PATH I299
R 3
J 0
(-1550 2975);
DISPLAY 0.978723 (-1550 2975);
PAINT WHITE (-1550 2975);
DISPLAY INVISIBLE (-1550 2975);
FORCEPROP 2 LAST ROOM PVPP_KLM_VR
R 3
J 0
(-1550 2975);
DISPLAY 1.659574 (-1550 2975);
PAINT GREEN (-1550 2975);
DISPLAY INVISIBLE (-1550 2975);
FORCEPROP 2 LAST CDS_LOCATION R7B11
J 0
(-1600 2875);
DISPLAY 0.617021 (-1600 2875);
PAINT AQUA (-1600 2875);
DISPLAY INVISIBLE (-1600 2875);
FORCEPROP 2 LAST CDS_LIB mstr_discrete
J 0
(-1700 2925);
PAINT ORANGE (-1700 2925);
DISPLAY INVISIBLE (-1700 2925);
FORCEADD RES..1
(-2400 2450);
FORCEPROP 1 LAST LOCATION R7B16
J 0
(-2450 2500);
DISPLAY 0.617021 (-2450 2500);
PAINT AQUA (-2450 2500);
FORCEPROP 1 LASTPIN (-2300 2450) $PN 2
J 0
(-2338 2462);
DISPLAY 0.617021 (-2338 2462);
PAINT ORANGE (-2338 2462);
FORCEPROP 1 LASTPIN (-2500 2450) $PN 1
J 0
(-2488 2462);
DISPLAY 0.617021 (-2488 2462);
PAINT ORANGE (-2488 2462);
FORCEPROP 1 LAST VALUE 7.87K
J 2
(-2500 2325);
DISPLAY 0.617021 (-2500 2325);
PAINT SKYBLUE (-2500 2325);
FORCEPROP 1 LAST PART_NUMBER G21796-242
J 0
(-2550 2375);
DISPLAY 0.617021 (-2550 2375);
PAINT BLUE (-2550 2375);
FORCEPROP 1 LAST PACK_TYPE 0402
J 0
(-2350 2325);
DISPLAY 0.617021 (-2350 2325);
PAINT SKYBLUE (-2350 2325);
FORCEPROP 1 LAST MATERIAL CHIP
J 0
(-2400 2275);
DISPLAY 0.617021 (-2400 2275);
PAINT SKYBLUE (-2400 2275);
FORCEPROP 1 LAST TOLERANCE 1.0%
J 0
(-2450 2325);
DISPLAY 0.617021 (-2450 2325);
PAINT SKYBLUE (-2450 2325);
FORCEPROP 1 LAST WATTAGE 1/16W
J 2
(-2425 2275);
DISPLAY 0.617021 (-2425 2275);
PAINT SKYBLUE (-2425 2275);
FORCEPROP 1 LAST PATH I300
J 0
(-2450 2600);
DISPLAY 0.978723 (-2450 2600);
PAINT WHITE (-2450 2600);
DISPLAY INVISIBLE (-2450 2600);
FORCEPROP 2 LAST REUSE_ID 13
J 0
(-2450 2650);
DISPLAY 1.042553 (-2450 2650);
PAINT ORANGE (-2450 2650);
DISPLAY INVISIBLE (-2450 2650);
FORCEPROP 2 LAST SEC_TYPE 0402
J 0
(-2450 2650);
DISPLAY 1.021277 (-2450 2650);
PAINT ORANGE (-2450 2650);
DISPLAY INVISIBLE (-2450 2650);
FORCEPROP 0 LAST SEC 1
J 0
(-2450 2550);
PAINT MONO (-2450 2550);
DISPLAY INVISIBLE (-2450 2550);
FORCEPROP 2 LAST ROOM PVPP_KLM_VR
J 0
(-2400 2450);
PAINT GREEN (-2400 2450);
DISPLAY INVISIBLE (-2400 2450);
FORCEPROP 2 LAST CDS_LOCATION R7B16
J 0
(-2450 2500);
DISPLAY 0.617021 (-2450 2500);
PAINT AQUA (-2450 2500);
DISPLAY INVISIBLE (-2450 2500);
FORCEPROP 2 LAST CDS_LIB mstr_discrete
J 0
(-2400 2450);
PAINT MONO (-2400 2450);
DISPLAY INVISIBLE (-2400 2450);
FORCEPROP 2 LAST BOM_COST PVPP_KLM_VR
J 0
(-2400 2450);
PAINT WHITE (-2400 2450);
DISPLAY INVISIBLE (-2400 2450);
FORCEADD CAP..2
R 2
(-2600 2825);
FORCEPROP 1 LASTPIN (-2700 2825) $PN 2
J 2
(-2685 2840);
DISPLAY 0.617021 (-2685 2840);
PAINT ORANGE (-2685 2840);
FORCEPROP 1 LAST TOLERANCE 5%
J 0
(-2600 2675);
DISPLAY 0.617021 (-2600 2675);
PAINT SKYBLUE (-2600 2675);
FORCEPROP 1 LAST PACK_TYPE 0402LF
J 1
(-2750 2725);
DISPLAY 0.617021 (-2750 2725);
PAINT SKYBLUE (-2750 2725);
FORCEPROP 1 LAST PART_NUMBER A36095-026
J 1
(-2725 2675);
DISPLAY 0.617021 (-2725 2675);
PAINT BLUE (-2725 2675);
FORCEPROP 1 LAST VOLTAGE 50V
J 2
(-2600 2725);
DISPLAY 0.617021 (-2600 2725);
PAINT SKYBLUE (-2600 2725);
FORCEPROP 1 LASTPIN (-2500 2825) $PN 1
J 2
(-2490 2840);
DISPLAY 0.617021 (-2490 2840);
PAINT ORANGE (-2490 2840);
FORCEPROP 1 LAST VALUE 100.0PF
J 0
(-2600 2725);
DISPLAY 0.617021 (-2600 2725);
PAINT SKYBLUE (-2600 2725);
FORCEPROP 1 LAST MATERIAL COG
J 2
(-2450 2675);
DISPLAY 0.617021 (-2450 2675);
PAINT SKYBLUE (-2450 2675);
FORCEPROP 1 LAST LOCATION C7B10
J 1
(-2600 2875);
DISPLAY 0.617021 (-2600 2875);
PAINT AQUA (-2600 2875);
FORCEPROP 2 LAST REUSE_ID 27
J 0
(-2600 3075);
DISPLAY 1.042553 (-2600 3075);
PAINT ORANGE (-2600 3075);
DISPLAY INVISIBLE (-2600 3075);
FORCEPROP 2 LAST SEC_TYPE 0402LF
J 0
(-2600 3075);
DISPLAY 1.021277 (-2600 3075);
PAINT ORANGE (-2600 3075);
DISPLAY INVISIBLE (-2600 3075);
FORCEPROP 2 LAST SEC 1
J 0
(-2600 3075);
DISPLAY 0.680851 (-2600 3075);
PAINT MONO (-2600 3075);
DISPLAY INVISIBLE (-2600 3075);
FORCEPROP 2 LAST ROOM PVPP_KLM_VR
J 2
(-2600 2950);
DISPLAY 0.765957 (-2600 2950);
PAINT GREEN (-2600 2950);
DISPLAY INVISIBLE (-2600 2950);
FORCEPROP 2 LAST CDS_LOCATION C7B10
J 1
(-2600 2875);
DISPLAY 0.617021 (-2600 2875);
PAINT AQUA (-2600 2875);
DISPLAY INVISIBLE (-2600 2875);
FORCEPROP 2 LAST CDS_LIB mstr_discrete
J 0
(-2600 2825);
PAINT ORANGE (-2600 2825);
DISPLAY INVISIBLE (-2600 2825);
FORCEPROP 1 LAST PATH I301
J 2
(-2600 3025);
DISPLAY 0.978723 (-2600 3025);
PAINT WHITE (-2600 3025);
DISPLAY INVISIBLE (-2600 3025);
FORCEPROP 2 LAST BOM_COST PVPP_KLM_VR
J 0
(-2645 2985);
DISPLAY 1.042553 (-2645 2985);
PAINT WHITE (-2645 2985);
DISPLAY INVISIBLE (-2645 2985);
FORCEADD CAP..1
(-1350 1775);
FORCEPROP 1 LAST PART_NUMBER A36096-075
J 0
(-1300 1625);
DISPLAY 0.617021 (-1300 1625);
PAINT BLUE (-1300 1625);
FORCEPROP 1 LAST PACK_TYPE 0402LF
J 0
(-1300 1575);
DISPLAY 0.617021 (-1300 1575);
PAINT SKYBLUE (-1300 1575);
FORCEPROP 1 LAST TOLERANCE 10%
J 0
(-1300 1725);
DISPLAY 0.617021 (-1300 1725);
PAINT SKYBLUE (-1300 1725);
FORCEPROP 1 LAST LOCATION C7B13
J 0
(-1300 1875);
DISPLAY 0.617021 (-1300 1875);
PAINT AQUA (-1300 1875);
FORCEPROP 1 LASTPIN (-1350 1675) $PN 2
J 0
(-1340 1655);
DISPLAY 0.617021 (-1340 1655);
PAINT ORANGE (-1340 1655);
FORCEPROP 1 LAST MATERIAL X7R
J 0
(-1300 1675);
DISPLAY 0.617021 (-1300 1675);
PAINT SKYBLUE (-1300 1675);
FORCEPROP 1 LAST VOLTAGE 50V
J 0
(-1300 1775);
DISPLAY 0.617021 (-1300 1775);
PAINT SKYBLUE (-1300 1775);
FORCEPROP 1 LAST VALUE 2200PF
J 0
(-1300 1825);
DISPLAY 0.617021 (-1300 1825);
PAINT SKYBLUE (-1300 1825);
FORCEPROP 1 LASTPIN (-1350 1875) $PN 1
J 0
(-1340 1855);
DISPLAY 0.617021 (-1340 1855);
PAINT ORANGE (-1340 1855);
FORCEPROP 2 LAST SEC 1
J 0
(-1300 1975);
DISPLAY 0.680851 (-1300 1975);
PAINT MONO (-1300 1975);
DISPLAY INVISIBLE (-1300 1975);
FORCEPROP 2 LAST CDS_LIB mstr_discrete
J 0
(-1350 1775);
PAINT ORANGE (-1350 1775);
DISPLAY INVISIBLE (-1350 1775);
FORCEPROP 2 LAST BOM_COST PVPP_KLM_VR
J 0
(-1300 1925);
DISPLAY 1.042553 (-1300 1925);
PAINT WHITE (-1300 1925);
DISPLAY INVISIBLE (-1300 1925);
FORCEPROP 2 LAST CDS_LOCATION C7B13
J 0
(-1300 1875);
DISPLAY 0.617021 (-1300 1875);
PAINT AQUA (-1300 1875);
DISPLAY INVISIBLE (-1300 1875);
FORCEPROP 1 LAST PATH I302
J 0
(-1300 1925);
DISPLAY 0.978723 (-1300 1925);
PAINT WHITE (-1300 1925);
DISPLAY INVISIBLE (-1300 1925);
FORCEPROP 2 LAST ROOM PVPP_KLM_VR
J 0
(-1300 1900);
PAINT GREEN (-1300 1900);
DISPLAY INVISIBLE (-1300 1900);
FORCEPROP 2 LAST REUSE_ID 26
J 0
(-1300 1975);
DISPLAY 1.042553 (-1300 1975);
PAINT ORANGE (-1300 1975);
DISPLAY INVISIBLE (-1300 1975);
FORCEPROP 2 LAST SEC_TYPE 0402LF
J 0
(-1300 1975);
DISPLAY 1.021277 (-1300 1975);
PAINT ORANGE (-1300 1975);
DISPLAY INVISIBLE (-1300 1975);
FORCEPROP 0 LAST SPOF TRUE
J 0
(-1300 1975);
DISPLAY 1.021277 (-1300 1975);
PAINT ORANGE (-1300 1975);
DISPLAY INVISIBLE (-1300 1975);
FORCEADD RES..2
(-1700 1850);
FORCEPROP 1 LAST PART_NUMBER G21796-040
J 0
(-1685 1675);
DISPLAY 0.617021 (-1685 1675);
PAINT BLUE (-1685 1675);
FORCEPROP 1 LAST MATERIAL CHIP
J 0
(-1660 1725);
DISPLAY 0.617021 (-1660 1725);
PAINT SKYBLUE (-1660 1725);
FORCEPROP 1 LAST PACK_TYPE 0402
J 0
(-1660 1775);
DISPLAY 0.617021 (-1660 1775);
PAINT SKYBLUE (-1660 1775);
FORCEPROP 1 LAST WATTAGE 1/16W
J 0
(-1660 1825);
DISPLAY 0.617021 (-1660 1825);
PAINT SKYBLUE (-1660 1825);
FORCEPROP 1 LAST TOLERANCE 1%
J 0
(-1655 1875);
DISPLAY 0.617021 (-1655 1875);
PAINT SKYBLUE (-1655 1875);
FORCEPROP 1 LASTPIN (-1700 1750) $PN 2
J 0
(-1695 1760);
DISPLAY 0.617021 (-1695 1760);
PAINT WHITE (-1695 1760);
FORCEPROP 1 LASTPIN (-1700 1950) $PN 1
J 0
(-1695 1912);
DISPLAY 0.617021 (-1695 1912);
PAINT WHITE (-1695 1912);
FORCEPROP 1 LAST VALUE 20.0K
J 0
(-1655 1925);
DISPLAY 0.617021 (-1655 1925);
PAINT SKYBLUE (-1655 1925);
FORCEPROP 1 LAST LOCATION R7B15
J 0
(-1655 1975);
DISPLAY 0.617021 (-1655 1975);
PAINT AQUA (-1655 1975);
FORCEPROP 2 LAST CDS_LIB mstr_discrete
J 0
(-1700 1850);
PAINT MONO (-1700 1850);
DISPLAY INVISIBLE (-1700 1850);
FORCEPROP 2 LAST CDS_LOCATION R7B15
J 0
(-1655 1975);
DISPLAY 0.617021 (-1655 1975);
PAINT AQUA (-1655 1975);
DISPLAY INVISIBLE (-1655 1975);
FORCEPROP 0 LAST SPOF TRUE
J 0
(-1650 2075);
DISPLAY 1.021277 (-1650 2075);
PAINT ORANGE (-1650 2075);
DISPLAY INVISIBLE (-1650 2075);
FORCEPROP 2 LAST CDS_SEC 1
J 0
(-1650 2075);
DISPLAY 1.042553 (-1650 2075);
PAINT ORANGE (-1650 2075);
DISPLAY INVISIBLE (-1650 2075);
FORCEPROP 2 LAST ROOM PVPP_KLM_VR
J 0
(-1655 2005);
PAINT GREEN (-1655 2005);
DISPLAY INVISIBLE (-1655 2005);
FORCEPROP 1 LAST PATH I303
J 0
(-1650 2025);
DISPLAY 0.978723 (-1650 2025);
PAINT WHITE (-1650 2025);
DISPLAY INVISIBLE (-1650 2025);
FORCEPROP 2 LAST REUSE_ID 9
J 0
(-1650 2075);
DISPLAY 1.042553 (-1650 2075);
PAINT ORANGE (-1650 2075);
DISPLAY INVISIBLE (-1650 2075);
FORCEPROP 2 LAST BOM_COST PVPP_KLM_VR
J 0
(-1655 2030);
DISPLAY 1.042553 (-1655 2030);
PAINT WHITE (-1655 2030);
DISPLAY INVISIBLE (-1655 2030);
FORCEPROP 2 LAST $SEC 1
J 0
(-1650 2075);
DISPLAY 0.680851 (-1650 2075);
PAINT MONO (-1650 2075);
DISPLAY INVISIBLE (-1650 2075);
FORCEADD CAP..2
R 2
(-3200 2450);
FORCEPROP 1 LASTPIN (-3300 2450) $PN 2
J 2
(-3285 2465);
DISPLAY 0.617021 (-3285 2465);
PAINT ORANGE (-3285 2465);
FORCEPROP 1 LASTPIN (-3100 2450) $PN 1
J 2
(-3090 2465);
DISPLAY 0.617021 (-3090 2465);
PAINT ORANGE (-3090 2465);
FORCEPROP 1 LAST LOCATION C7B14
J 1
(-3200 2525);
DISPLAY 0.617021 (-3200 2525);
PAINT AQUA (-3200 2525);
FORCEPROP 1 LAST MATERIAL X7R
J 2
(-3200 2300);
DISPLAY 0.617021 (-3200 2300);
PAINT SKYBLUE (-3200 2300);
FORCEPROP 1 LAST VOLTAGE 50V
J 2
(-3200 2350);
DISPLAY 0.617021 (-3200 2350);
PAINT SKYBLUE (-3200 2350);
FORCEPROP 1 LAST VALUE 2200PF
J 0
(-3200 2350);
DISPLAY 0.617021 (-3200 2350);
PAINT SKYBLUE (-3200 2350);
FORCEPROP 1 LAST TOLERANCE 10%
J 0
(-3200 2300);
DISPLAY 0.617021 (-3200 2300);
PAINT SKYBLUE (-3200 2300);
FORCEPROP 1 LAST PACK_TYPE 0402LF
J 1
(-3200 2250);
DISPLAY 0.617021 (-3200 2250);
PAINT SKYBLUE (-3200 2250);
FORCEPROP 1 LAST PART_NUMBER A36096-075
J 1
(-3150 2200);
DISPLAY 0.617021 (-3150 2200);
PAINT BLUE (-3150 2200);
FORCEPROP 2 LAST ROOM PVPP_KLM_VR
J 2
(-3200 2575);
DISPLAY 0.765957 (-3200 2575);
PAINT GREEN (-3200 2575);
DISPLAY INVISIBLE (-3200 2575);
FORCEPROP 1 LAST PATH I306
J 2
(-3200 2650);
DISPLAY 0.978723 (-3200 2650);
PAINT WHITE (-3200 2650);
DISPLAY INVISIBLE (-3200 2650);
FORCEPROP 2 LAST SEC 1
J 0
(-3200 2700);
DISPLAY 0.680851 (-3200 2700);
PAINT MONO (-3200 2700);
DISPLAY INVISIBLE (-3200 2700);
FORCEPROP 2 LAST REUSE_ID 27
J 0
(-3200 2700);
DISPLAY 1.042553 (-3200 2700);
PAINT ORANGE (-3200 2700);
DISPLAY INVISIBLE (-3200 2700);
FORCEPROP 2 LAST BOM_COST PVPP_KLM_VR
J 0
(-3245 2610);
DISPLAY 1.042553 (-3245 2610);
PAINT WHITE (-3245 2610);
DISPLAY INVISIBLE (-3245 2610);
FORCEPROP 2 LAST SEC_TYPE 0402LF
J 0
(-3200 2700);
DISPLAY 1.021277 (-3200 2700);
PAINT ORANGE (-3200 2700);
DISPLAY INVISIBLE (-3200 2700);
FORCEPROP 2 LAST CDS_LOCATION C7B14
J 1
(-3200 2525);
DISPLAY 0.617021 (-3200 2525);
PAINT AQUA (-3200 2525);
DISPLAY INVISIBLE (-3200 2525);
FORCEPROP 2 LAST CDS_LIB mstr_discrete
J 0
(-3200 2450);
PAINT ORANGE (-3200 2450);
DISPLAY INVISIBLE (-3200 2450);
FORCEADD RES..1
(-6500 2825);
FORCEPROP 1 LAST LOCATION R7B9
J 0
(-6550 2875);
DISPLAY 0.617021 (-6550 2875);
PAINT AQUA (-6550 2875);
FORCEPROP 1 LAST MATERIAL CHIP
J 0
(-6500 2675);
DISPLAY 0.617021 (-6500 2675);
PAINT SKYBLUE (-6500 2675);
FORCEPROP 1 LAST PACK_TYPE 0402
J 0
(-6425 2725);
DISPLAY 0.617021 (-6425 2725);
PAINT SKYBLUE (-6425 2725);
FORCEPROP 1 LAST TOLERANCE 5%
J 0
(-6550 2725);
DISPLAY 0.617021 (-6550 2725);
PAINT SKYBLUE (-6550 2725);
FORCEPROP 1 LAST PART_NUMBER G21497-005
J 0
(-6650 2775);
DISPLAY 0.617021 (-6650 2775);
PAINT BLUE (-6650 2775);
FORCEPROP 1 LASTPIN (-6600 2825) $PN 1
J 0
(-6588 2837);
DISPLAY 0.617021 (-6588 2837);
PAINT ORANGE (-6588 2837);
FORCEPROP 1 LAST WATTAGE 1/16W
J 2
(-6525 2675);
DISPLAY 0.617021 (-6525 2675);
PAINT SKYBLUE (-6525 2675);
FORCEPROP 1 LASTPIN (-6400 2825) $PN 2
J 0
(-6438 2837);
DISPLAY 0.617021 (-6438 2837);
PAINT ORANGE (-6438 2837);
FORCEPROP 1 LAST VALUE 0.0
J 2
(-6600 2725);
DISPLAY 0.617021 (-6600 2725);
PAINT SKYBLUE (-6600 2725);
FORCEPROP 2 LAST ROOM PVCCIN_CPU0_VR
J 0
(-6550 2925);
DISPLAY 1.361702 (-6550 2925);
PAINT ORANGE (-6550 2925);
DISPLAY INVISIBLE (-6550 2925);
FORCEPROP 1 LAST PATH I307
J 0
(-6550 2975);
DISPLAY 0.978723 (-6550 2975);
PAINT WHITE (-6550 2975);
DISPLAY INVISIBLE (-6550 2975);
FORCEPROP 2 LAST CDS_LOCATION R7B9
J 0
(-6550 2875);
DISPLAY 0.617021 (-6550 2875);
PAINT AQUA (-6550 2875);
DISPLAY INVISIBLE (-6550 2875);
FORCEPROP 2 LAST SEC 1
J 0
(-6550 3025);
PAINT MONO (-6550 3025);
DISPLAY INVISIBLE (-6550 3025);
FORCEPROP 2 LAST CDS_LIB mstr_discrete
J 0
(-6500 2825);
PAINT ORANGE (-6500 2825);
DISPLAY INVISIBLE (-6500 2825);
FORCEPROP 2 LAST SEC_TYPE 0402
J 0
(-6550 3025);
DISPLAY 1.021277 (-6550 3025);
PAINT ORANGE (-6550 3025);
DISPLAY INVISIBLE (-6550 3025);
FORCEADD AGND_SCSI..1
(-1700 950);
FORCEPROP 3 LASTPIN (-1700 1000) SIG_NAME AGND_PVPP_DEF\g
J 0
(-1690 1010);
DISPLAY 0.659574 (-1690 1010);
PAINT MONO (-1690 1010);
DISPLAY INVISIBLE (-1690 1010);
FORCEPROP 1 LAST HDL_POWER AGND_PVPP_DEF
J 1
(-1625 875);
DISPLAY 0.617021 (-1625 875);
PAINT GREEN (-1625 875);
FORCEPROP 1 LAST BODY_TYPE PLUMBING
J 0
(-1745 907);
DISPLAY 0.340426 (-1745 907);
PAINT GREEN (-1745 907);
DISPLAY INVISIBLE (-1745 907);
FORCEPROP 2 LAST BOM_COST PVPP_KLM_VR
J 0
(-1850 900);
DISPLAY 1.042553 (-1850 900);
PAINT WHITE (-1850 900);
DISPLAY INVISIBLE (-1850 900);
FORCEPROP 2 LAST ROOM PVPP_KLM_VR
J 0
(-1850 900);
DISPLAY 1.042553 (-1850 900);
PAINT GREEN (-1850 900);
DISPLAY INVISIBLE (-1850 900);
FORCEPROP 1 LAST VOLTAGE 0.0V
J 0
(-1745 907);
DISPLAY 0.340426 (-1745 907);
PAINT SKYBLUE (-1745 907);
DISPLAY INVISIBLE (-1745 907);
FORCEPROP 1 LAST PATH I308
J 0
(-1625 950);
DISPLAY 0.872340 (-1625 950);
PAINT AQUA (-1625 950);
DISPLAY INVISIBLE (-1625 950);
FORCEPROP 2 LAST CDS_LIB mstr_symbols
J 0
(-1700 950);
PAINT ORANGE (-1700 950);
DISPLAY INVISIBLE (-1700 950);
FORCEADD SC22U16V5MX-4-GP..1
(-7600 4100);
FORCEPROP 2 LASTPIN (-7600 4025) $PN 2
R 1
J 2
(-7610 4015);
DISPLAY 0.808511 (-7610 4015);
PAINT ORANGE (-7610 4015);
FORCEPROP 2 LAST TOLERANCE 20%
J 0
(-7500 4100);
DISPLAY 0.638298 (-7500 4100);
PAINT GREEN (-7500 4100);
FORCEPROP 2 LAST RATED 16V
J 0
(-7500 4050);
DISPLAY 0.638298 (-7500 4050);
PAINT GREEN (-7500 4050);
FORCEPROP 2 LAST TYPE X6S
J 0
(-7500 4000);
DISPLAY 0.638298 (-7500 4000);
PAINT GREEN (-7500 4000);
FORCEPROP 2 LAST PACK_SIZE 0805
J 0
(-7500 3950);
DISPLAY 0.638298 (-7500 3950);
PAINT GREEN (-7500 3950);
FORCEPROP 2 LAST ATTRIBUTE 22UF
J 0
(-7500 4150);
DISPLAY 0.638298 (-7500 4150);
PAINT GREEN (-7500 4150);
FORCEPROP 1 LAST LOCATION C7B8
J 0
(-7500 4210);
DISPLAY 0.617021 (-7500 4210);
PAINT GREEN (-7500 4210);
FORCEPROP 1 LAST VALUE SC22U16V5MX-4-GP
R 1
J 0
(-7525 3895);
DISPLAY 0.617021 (-7525 3895);
PAINT GREEN (-7525 3895);
FORCEPROP 2 LASTPIN (-7600 4175) $PN 1
R 1
J 0
(-7610 4185);
DISPLAY 0.808511 (-7610 4185);
PAINT ORANGE (-7610 4185);
FORCEPROP 1 LAST CDS_LMAN_SYM_OUTLINE -50,25,50,-25
J 0
(-7600 4100);
DISPLAY 0.468085 (-7600 4100);
PAINT GREEN (-7600 4100);
DISPLAY INVISIBLE (-7600 4100);
FORCEPROP 2 LAST CDS_LIB w_hdl
J 0
(-7600 4100);
PAINT MONO (-7600 4100);
DISPLAY INVISIBLE (-7600 4100);
FORCEPROP 1 LAST PART_NUMBER 078.22611.0811
J 0
(-7600 4100);
DISPLAY 0.617021 (-7600 4100);
PAINT GREEN (-7600 4100);
DISPLAY INVISIBLE (-7600 4100);
FORCEPROP 2 LAST SEC_TYPE SMD-BCG5
J 0
(-7575 4175);
DISPLAY 1.021277 (-7575 4175);
PAINT ORANGE (-7575 4175);
DISPLAY INVISIBLE (-7575 4175);
FORCEPROP 2 LAST SEC 1
J 0
(-7575 4175);
DISPLAY 0.680851 (-7575 4175);
PAINT MONO (-7575 4175);
DISPLAY INVISIBLE (-7575 4175);
FORCEPROP 1 LAST PACK_TYPE SMD-BCG5
J 0
(-7600 4100);
DISPLAY 0.617021 (-7600 4100);
PAINT GREEN (-7600 4100);
DISPLAY INVISIBLE (-7600 4100);
FORCEPROP 1 LAST PATH I309
J 0
(-7600 4100);
DISPLAY 0.617021 (-7600 4100);
PAINT GREEN (-7600 4100);
DISPLAY INVISIBLE (-7600 4100);
FORCEADD GND..1
(-7300 3850);
FORCEPROP 3 LASTPIN (-7300 3900) SIG_NAME GND\g
J 0
(-7290 3910);
DISPLAY 0.659574 (-7290 3910);
PAINT MONO (-7290 3910);
DISPLAY INVISIBLE (-7290 3910);
FORCEPROP 1 LAST SIZE 1B
J 0
(-7225 3800);
DISPLAY 0.872340 (-7225 3800);
PAINT GREEN (-7225 3800);
DISPLAY INVISIBLE (-7225 3800);
FORCEPROP 1 LAST VOLTAGE 0
J 0
(-7300 3850);
PAINT SKYBLUE (-7300 3850);
DISPLAY INVISIBLE (-7300 3850);
FORCEPROP 2 LAST ROOM PVPP_KLM_VR
J 0
(-7875 3925);
DISPLAY 1.042553 (-7875 3925);
PAINT GREEN (-7875 3925);
DISPLAY INVISIBLE (-7875 3925);
FORCEPROP 2 LAST BOM_COST PVPP_KLM_VR
J 0
(-8150 3925);
DISPLAY 1.042553 (-8150 3925);
PAINT WHITE (-8150 3925);
DISPLAY INVISIBLE (-8150 3925);
FORCEPROP 2 LAST CDS_LIB mstr_symbols
J 0
(-7300 3850);
PAINT MONO (-7300 3850);
DISPLAY INVISIBLE (-7300 3850);
FORCEPROP 1 LAST PATH I310
J 0
(-7225 3850);
DISPLAY 0.872340 (-7225 3850);
PAINT AQUA (-7225 3850);
DISPLAY INVISIBLE (-7225 3850);
FORCEPROP 1 LAST BODY_TYPE PLUMBING
J 0
(-7345 3807);
DISPLAY 0.340426 (-7345 3807);
PAINT GREEN (-7345 3807);
DISPLAY INVISIBLE (-7345 3807);
FORCEPROP 1 LAST HDL_POWER GND
J 0
(-7300 4000);
DISPLAY 0.872340 (-7300 4000);
PAINT GREEN (-7300 4000);
DISPLAY INVISIBLE (-7300 4000);
FORCEADD SC22U16V5MX-4-GP..1
(-7300 4100);
FORCEPROP 2 LASTPIN (-7300 4175) $PN 1
R 1
J 0
(-7310 4185);
DISPLAY 0.808511 (-7310 4185);
PAINT ORANGE (-7310 4185);
FORCEPROP 2 LASTPIN (-7300 4025) $PN 2
R 1
J 2
(-7310 4015);
DISPLAY 0.808511 (-7310 4015);
PAINT ORANGE (-7310 4015);
FORCEPROP 1 LAST LOCATION C22W7
J 0
(-7200 4210);
DISPLAY 0.617021 (-7200 4210);
PAINT GREEN (-7200 4210);
FORCEPROP 2 LAST TOLERANCE 20%
J 0
(-7200 4100);
DISPLAY 0.638298 (-7200 4100);
PAINT GREEN (-7200 4100);
FORCEPROP 2 LAST RATED 16V
J 0
(-7200 4050);
DISPLAY 0.638298 (-7200 4050);
PAINT GREEN (-7200 4050);
FORCEPROP 2 LAST TYPE X6S
J 0
(-7200 4000);
DISPLAY 0.638298 (-7200 4000);
PAINT GREEN (-7200 4000);
FORCEPROP 2 LAST PACK_SIZE 0805
J 0
(-7200 3950);
DISPLAY 0.638298 (-7200 3950);
PAINT GREEN (-7200 3950);
FORCEPROP 1 LAST VALUE SC22U16V5MX-4-GP
R 1
J 0
(-7225 3895);
DISPLAY 0.617021 (-7225 3895);
PAINT GREEN (-7225 3895);
FORCEPROP 2 LAST ATTRIBUTE 22UF
J 0
(-7200 4150);
DISPLAY 0.638298 (-7200 4150);
PAINT GREEN (-7200 4150);
FORCEPROP 1 LAST PATH I311
J 0
(-7300 4100);
DISPLAY 0.617021 (-7300 4100);
PAINT GREEN (-7300 4100);
DISPLAY INVISIBLE (-7300 4100);
FORCEPROP 1 LAST CDS_LMAN_SYM_OUTLINE -50,25,50,-25
J 0
(-7300 4100);
DISPLAY 0.468085 (-7300 4100);
PAINT GREEN (-7300 4100);
DISPLAY INVISIBLE (-7300 4100);
FORCEPROP 2 LAST CDS_LIB w_hdl
J 0
(-7300 4100);
PAINT MONO (-7300 4100);
DISPLAY INVISIBLE (-7300 4100);
FORCEPROP 1 LAST PART_NUMBER 078.22611.0811
J 0
(-7300 4100);
DISPLAY 0.617021 (-7300 4100);
PAINT GREEN (-7300 4100);
DISPLAY INVISIBLE (-7300 4100);
FORCEPROP 2 LAST SEC_TYPE SMD-BCG5
J 0
(-7275 4175);
DISPLAY 1.021277 (-7275 4175);
PAINT ORANGE (-7275 4175);
DISPLAY INVISIBLE (-7275 4175);
FORCEPROP 2 LAST SEC 1
J 0
(-7275 4175);
DISPLAY 0.680851 (-7275 4175);
PAINT MONO (-7275 4175);
DISPLAY INVISIBLE (-7275 4175);
FORCEPROP 1 LAST PACK_TYPE SMD-BCG5
J 0
(-7300 4100);
DISPLAY 0.617021 (-7300 4100);
PAINT GREEN (-7300 4100);
DISPLAY INVISIBLE (-7300 4100);
FORCEADD GND..1
(-7600 3850);
FORCEPROP 3 LASTPIN (-7600 3900) SIG_NAME GND\g
J 0
(-7590 3910);
DISPLAY 0.659574 (-7590 3910);
PAINT MONO (-7590 3910);
DISPLAY INVISIBLE (-7590 3910);
FORCEPROP 1 LAST SIZE 1B
J 0
(-7525 3800);
DISPLAY 0.872340 (-7525 3800);
PAINT GREEN (-7525 3800);
DISPLAY INVISIBLE (-7525 3800);
FORCEPROP 1 LAST VOLTAGE 0
J 0
(-7600 3850);
PAINT SKYBLUE (-7600 3850);
DISPLAY INVISIBLE (-7600 3850);
FORCEPROP 2 LAST ROOM PVPP_KLM_VR
J 0
(-8175 3925);
DISPLAY 1.042553 (-8175 3925);
PAINT GREEN (-8175 3925);
DISPLAY INVISIBLE (-8175 3925);
FORCEPROP 2 LAST BOM_COST PVPP_KLM_VR
J 0
(-8450 3925);
DISPLAY 1.042553 (-8450 3925);
PAINT WHITE (-8450 3925);
DISPLAY INVISIBLE (-8450 3925);
FORCEPROP 2 LAST CDS_LIB mstr_symbols
J 0
(-7600 3850);
PAINT MONO (-7600 3850);
DISPLAY INVISIBLE (-7600 3850);
FORCEPROP 1 LAST PATH I312
J 0
(-7525 3850);
DISPLAY 0.872340 (-7525 3850);
PAINT AQUA (-7525 3850);
DISPLAY INVISIBLE (-7525 3850);
FORCEPROP 1 LAST BODY_TYPE PLUMBING
J 0
(-7645 3807);
DISPLAY 0.340426 (-7645 3807);
PAINT GREEN (-7645 3807);
DISPLAY INVISIBLE (-7645 3807);
FORCEPROP 1 LAST HDL_POWER GND
J 0
(-7600 4000);
DISPLAY 0.872340 (-7600 4000);
PAINT GREEN (-7600 4000);
DISPLAY INVISIBLE (-7600 4000);
FORCEADD RES..1
(-4500 4175);
FORCEPROP 1 LAST WATTAGE 1/10W
J 0
(-4500 4025);
DISPLAY 0.617021 (-4500 4025);
PAINT SKYBLUE (-4500 4025);
FORCEPROP 1 LASTPIN (-4400 4175) $PN 2
J 0
(-4438 4187);
DISPLAY 0.787234 (-4438 4187);
PAINT ORANGE (-4438 4187);
FORCEPROP 1 LAST PACK_TYPE 0603
J 0
(-4625 4025);
DISPLAY 0.617021 (-4625 4025);
PAINT SKYBLUE (-4625 4025);
FORCEPROP 1 LASTPIN (-4600 4175) $PN 1
J 0
(-4588 4187);
DISPLAY 0.787234 (-4588 4187);
PAINT ORANGE (-4588 4187);
FORCEPROP 1 LAST VALUE 0
J 0
(-4625 4075);
DISPLAY 0.617021 (-4625 4075);
PAINT SKYBLUE (-4625 4075);
FORCEPROP 1 LAST TOLERANCE 5.0%
J 0
(-4550 4075);
DISPLAY 0.617021 (-4550 4075);
PAINT SKYBLUE (-4550 4075);
FORCEPROP 1 LAST LOCATION R7B19
J 0
(-4600 4225);
DISPLAY 0.617021 (-4600 4225);
PAINT AQUA (-4600 4225);
FORCEPROP 1 LAST PART_NUMBER G22178-002
J 0
(-4625 4125);
DISPLAY 0.617021 (-4625 4125);
PAINT BLUE (-4625 4125);
FORCEPROP 1 LAST MATERIAL CHIP
J 0
(-4325 4125);
DISPLAY 0.617021 (-4325 4125);
PAINT SKYBLUE (-4325 4125);
FORCEPROP 0 LAST CDS_LOCATION R7B19
J 0
(-4425 4175);
PAINT MONO (-4425 4175);
DISPLAY INVISIBLE (-4425 4175);
FORCEPROP 0 LAST ROOM NIC_SPRV
J 0
(-4400 4300);
DISPLAY 1.021277 (-4400 4300);
PAINT ORANGE (-4400 4300);
DISPLAY INVISIBLE (-4400 4300);
FORCEPROP 0 LAST BOM_COST NT_GBE_BASE
J 0
(-4400 4400);
DISPLAY 1.021277 (-4400 4400);
PAINT ORANGE (-4400 4400);
DISPLAY INVISIBLE (-4400 4400);
FORCEPROP 2 LAST CDS_LIB mstr_discrete
J 0
(-4500 4175);
PAINT MONO (-4500 4175);
DISPLAY INVISIBLE (-4500 4175);
FORCEPROP 2 LAST SEC_TYPE 0603
J 0
(-4550 4375);
DISPLAY 1.021277 (-4550 4375);
PAINT ORANGE (-4550 4375);
DISPLAY INVISIBLE (-4550 4375);
FORCEPROP 0 LAST SEC 1
J 0
(-4750 4275);
DISPLAY 0.680851 (-4750 4275);
PAINT MONO (-4750 4275);
DISPLAY INVISIBLE (-4750 4275);
FORCEPROP 0 LAST CDS_SEC 1
J 0
(-4425 4175);
PAINT MONO (-4425 4175);
DISPLAY INVISIBLE (-4425 4175);
FORCEPROP 1 LAST PATH I313
J 0
(-4550 4325);
DISPLAY 0.978723 (-4550 4325);
PAINT WHITE (-4550 4325);
DISPLAY INVISIBLE (-4550 4325);
FORCEADD RES..2
(-1700 1300);
FORCEPROP 1 LAST TOLERANCE 1%
J 0
(-1655 1325);
DISPLAY 0.617021 (-1655 1325);
PAINT SKYBLUE (-1655 1325);
FORCEPROP 1 LAST WATTAGE 1/16W
J 0
(-1660 1275);
DISPLAY 0.617021 (-1660 1275);
PAINT SKYBLUE (-1660 1275);
FORCEPROP 1 LAST MATERIAL CHIP
J 0
(-1660 1225);
DISPLAY 0.617021 (-1660 1225);
PAINT SKYBLUE (-1660 1225);
FORCEPROP 1 LAST PART_NUMBER G21796-161
J 0
(-1660 1175);
DISPLAY 0.617021 (-1660 1175);
PAINT BLUE (-1660 1175);
FORCEPROP 1 LAST LOCATION R7B13
J 0
(-1655 1425);
DISPLAY 0.617021 (-1655 1425);
PAINT AQUA (-1655 1425);
FORCEPROP 1 LASTPIN (-1700 1200) $PN 2
J 0
(-1695 1210);
DISPLAY 0.617021 (-1695 1210);
PAINT ORANGE (-1695 1210);
FORCEPROP 1 LAST PACK_TYPE 0402
J 0
(-1660 1125);
DISPLAY 0.617021 (-1660 1125);
PAINT SKYBLUE (-1660 1125);
FORCEPROP 1 LASTPIN (-1700 1400) $PN 1
J 0
(-1695 1362);
DISPLAY 0.617021 (-1695 1362);
PAINT ORANGE (-1695 1362);
FORCEPROP 1 LAST VALUE 6.19K
J 0
(-1655 1375);
DISPLAY 0.617021 (-1655 1375);
PAINT SKYBLUE (-1655 1375);
FORCEPROP 1 LAST PATH I314
J 0
(-1650 1475);
DISPLAY 0.978723 (-1650 1475);
PAINT WHITE (-1650 1475);
DISPLAY INVISIBLE (-1650 1475);
FORCEPROP 0 LAST CDS_SEC 1
J 0
(-1650 1475);
PAINT MONO (-1650 1475);
DISPLAY INVISIBLE (-1650 1475);
FORCEPROP 2 LAST CDS_LIB mstr_discrete
J 0
(-1700 1300);
PAINT ORANGE (-1700 1300);
DISPLAY INVISIBLE (-1700 1300);
FORCEPROP 0 LAST ROOM IO_SLOT
J 0
(-1650 1525);
DISPLAY 1.021277 (-1650 1525);
PAINT ORANGE (-1650 1525);
DISPLAY INVISIBLE (-1650 1525);
FORCEPROP 2 LAST SEC_TYPE 0402
J 0
(-1650 1525);
DISPLAY 1.021277 (-1650 1525);
PAINT ORANGE (-1650 1525);
DISPLAY INVISIBLE (-1650 1525);
FORCEPROP 2 LAST SEC 1
J 0
(-1650 1525);
DISPLAY 0.680851 (-1650 1525);
PAINT MONO (-1650 1525);
DISPLAY INVISIBLE (-1650 1525);
FORCEPROP 0 LAST BOM_COST IO_SLOT
J 0
(-1650 1625);
DISPLAY 1.021277 (-1650 1625);
PAINT ORANGE (-1650 1625);
DISPLAY INVISIBLE (-1650 1625);
FORCEPROP 2 LAST CDS_LOCATION R7B13
J 0
(-1655 1425);
DISPLAY 0.617021 (-1655 1425);
PAINT AQUA (-1655 1425);
DISPLAY INVISIBLE (-1655 1425);
FORCEADD RES..2
R 2
(-5100 1650);
FORCEPROP 1 LASTPIN (-5100 1750) $PN 1
J 2
(-5105 1712);
DISPLAY 0.617021 (-5105 1712);
PAINT WHITE (-5105 1712);
FORCEPROP 1 LASTPIN (-5100 1550) $PN 2
J 2
(-5105 1560);
DISPLAY 0.617021 (-5105 1560);
PAINT WHITE (-5105 1560);
FORCEPROP 1 LAST TOLERANCE 1.0%
J 2
(-5145 1675);
DISPLAY 0.617021 (-5145 1675);
PAINT SKYBLUE (-5145 1675);
FORCEPROP 1 LAST PACK_TYPE 0402
J 2
(-5140 1475);
DISPLAY 0.617021 (-5140 1475);
PAINT SKYBLUE (-5140 1475);
FORCEPROP 1 LAST LOCATION R7B14
J 2
(-5145 1775);
DISPLAY 0.617021 (-5145 1775);
PAINT AQUA (-5145 1775);
FORCEPROP 1 LAST MATERIAL CHIP
J 2
(-5140 1575);
DISPLAY 0.617021 (-5140 1575);
PAINT SKYBLUE (-5140 1575);
FORCEPROP 1 LAST WATTAGE 1/16W
J 2
(-5140 1625);
DISPLAY 0.617021 (-5140 1625);
PAINT SKYBLUE (-5140 1625);
FORCEPROP 0 LAST NEW_VALUE 3.9K
J 0
(-5500 1375);
DISPLAY 0.638298 (-5500 1375);
PAINT BROWN (-5500 1375);
DISPLAY BOTH (-5500 1375);
FORCEPROP 0 LAST CONFIG 64.39015.6DL
J 0
(-5500 1425);
DISPLAY 0.638298 (-5500 1425);
PAINT BROWN (-5500 1425);
DISPLAY BOTH (-5500 1425);
FORCEPROP 2 LAST CDS_SEC 1
J 2
(-5000 2025);
DISPLAY 1.042553 (-5000 2025);
PAINT ORANGE (-5000 2025);
DISPLAY INVISIBLE (-5000 2025);
FORCEPROP 2 LAST $SEC 1
J 0
(-5150 1875);
DISPLAY 0.680851 (-5150 1875);
PAINT MONO (-5150 1875);
DISPLAY INVISIBLE (-5150 1875);
FORCEPROP 2 LAST CDS_LIB mstr_discrete
J 2
(-5100 1650);
PAINT MONO (-5100 1650);
DISPLAY INVISIBLE (-5100 1650);
FORCEPROP 2 LAST BOM_COST PVPP_KLM_VR
J 2
(-5100 1650);
PAINT WHITE (-5100 1650);
DISPLAY INVISIBLE (-5100 1650);
FORCEPROP 2 LAST ROOM PVPP_KLM_VR
J 2
(-5100 1650);
PAINT GREEN (-5100 1650);
DISPLAY INVISIBLE (-5100 1650);
FORCEPROP 1 LAST VALUE 7.87K
J 2
(-5145 1725);
DISPLAY 0.617021 (-5145 1725);
PAINT SKYBLUE (-5145 1725);
DISPLAY INVISIBLE (-5145 1725);
FORCEPROP 1 LAST PATH I315
J 2
(-5150 1825);
DISPLAY 0.978723 (-5150 1825);
PAINT WHITE (-5150 1825);
DISPLAY INVISIBLE (-5150 1825);
FORCEPROP 1 LAST PART_NUMBER G21796-242
J 2
(-5140 1525);
DISPLAY 0.617021 (-5140 1525);
PAINT BLUE (-5140 1525);
DISPLAY INVISIBLE (-5140 1525);
FORCEPROP 2 LAST CDS_LOCATION R7B14
J 2
(-5145 1775);
DISPLAY 0.617021 (-5145 1775);
PAINT AQUA (-5145 1775);
DISPLAY INVISIBLE (-5145 1775);
FORCEADD DNS..2
(-2870 3695);
PAINT RED (-2870 3695);
FORCEPROP 2 LAST CDS_LIB mstr_misc
J 0
(-2870 3695);
PAINT ORANGE (-2870 3695);
DISPLAY INVISIBLE (-2870 3695);
FORCEPROP 1 LAST COMMENT_BODY TRUE
R 1
J 0
(-2795 3470);
DISPLAY 0.872340 (-2795 3470);
PAINT GREEN (-2795 3470);
DISPLAY INVISIBLE (-2795 3470);
FORCEADD INTEL_CORP_BPAGE..1
(-800 50);
FORCEPROP 1 LAST CDS_CON_LAST_MODIFIED Fri Jun 16 17:49:23 2017
J 0
(-2225 375);
DISPLAY 0.659574 (-2225 375);
PAINT GREEN (-2225 375);
DISPLAY INVISIBLE (-2225 375);
FORCEPROP 1 LAST CUSTOM_TXT_CDS <CURRENT_DESIGN_SHEET> OF <TOTAL_DESIGN_SHEETS>
J 0
(-1300 75);
PAINT ORANGE (-1300 75);
FORCEPROP 2 LAST CUSTOM_TXT_CDS <XR_PAGE_TITLE>
J 0
(-8690 5300);
DISPLAY 0.638298 (-8690 5300);
PAINT PINK (-8690 5300);
DISPLAY INVISIBLE (-8690 5300);
FORCEPROP 2 LAST CUSTOM_TXT_CDS <CON_LAST_MODIFIED>
J 0
(-4800 150);
DISPLAY 0.957447 (-4800 150);
PAINT ORANGE (-4800 150);
FORCEPROP 1 LAST SCH_TITLE VPP DEF VR
J 0
(-8750 100);
DISPLAY 1.212766 (-8750 100);
PAINT GREEN (-8750 100);
FORCEPROP 2 LAST CDS_LIB mstr_symbols
J 0
(-800 50);
DISPLAY 0.489362 (-800 50);
PAINT ORANGE (-800 50);
DISPLAY INVISIBLE (-800 50);
FORCEPROP 2 LAST PAGE_BORDER TRUE
J 0
(-8690 5300);
DISPLAY 0.425532 (-8690 5300);
PAINT PINK (-8690 5300);
DISPLAY INVISIBLE (-8690 5300);
FORCEPROP 1 LAST COMMENT_BODY TRUE
J 0
(-788 62);
DISPLAY 0.319149 (-788 62);
PAINT GREEN (-788 62);
DISPLAY INVISIBLE (-788 62);
FORCEPROP 2 LAST CDS_XR_PAGE_TITLE CR-232 : @BASEBOARD_FAB2_LIB.BASEBOARD_FAB2(SCH_1):PAGE232
J 0
(-8690 5300);
DISPLAY 0.638298 (-8690 5300);
PAINT PINK (-8690 5300);
DISPLAY INVISIBLE (-8690 5300);
FORCEADD DNS..2
(-6820 2495);
PAINT RED (-6820 2495);
FORCEPROP 2 LAST CDS_LIB mstr_misc
J 0
(-6820 2495);
PAINT ORANGE (-6820 2495);
DISPLAY INVISIBLE (-6820 2495);
FORCEPROP 1 LAST COMMENT_BODY TRUE
R 1
J 0
(-6745 2270);
DISPLAY 0.872340 (-6745 2270);
PAINT GREEN (-6745 2270);
DISPLAY INVISIBLE (-6745 2270);
FORCEADD DNS..2
(-2895 3320);
PAINT RED (-2895 3320);
FORCEPROP 2 LAST CDS_LIB mstr_misc
J 0
(-2895 3320);
PAINT ORANGE (-2895 3320);
DISPLAY INVISIBLE (-2895 3320);
FORCEPROP 1 LAST COMMENT_BODY TRUE
R 1
J 0
(-2820 3095);
DISPLAY 0.872340 (-2820 3095);
PAINT GREEN (-2820 3095);
DISPLAY INVISIBLE (-2820 3095);
WIRE 16 -1 (-8600 1050)(-8600 1100);
WIRE 16 -1 (-8325 1050)(-8600 1050);
WIRE 16 -1 (-8600 1050)(-8600 975);
WIRE 16 -1 (-8050 1050)(-8325 1050);
WIRE 16 -1 (-8325 975)(-8325 1050);
WIRE 16 -1 (-7775 1050)(-8050 1050);
WIRE 16 -1 (-8050 975)(-8050 1050);
WIRE 16 -1 (-7500 1050)(-7775 1050);
WIRE 16 -1 (-7775 975)(-7775 1050);
WIRE 16 -1 (-7200 1050)(-7500 1050);
WIRE 16 -1 (-7500 975)(-7500 1050);
WIRE 16 -1 (-6925 1050)(-7200 1050);
WIRE 16 -1 (-7200 975)(-7200 1050);
WIRE 16 -1 (-6625 1050)(-6925 1050);
WIRE 16 -1 (-6925 1050)(-6925 975);
WIRE 16 -1 (-6325 1050)(-6625 1050);
WIRE 16 -1 (-6625 975)(-6625 1050);
WIRE 16 -1 (-6050 1050)(-6325 1050);
WIRE 16 -1 (-6325 975)(-6325 1050);
WIRE 16 -1 (-5775 1050)(-6050 1050);
WIRE 16 -1 (-6050 975)(-6050 1050);
WIRE 16 -1 (-5500 1050)(-5775 1050);
WIRE 16 -1 (-5775 975)(-5775 1050);
WIRE 16 -1 (-5500 975)(-5500 1050);
WIRE 16 -1 (-8600 550)(-8600 525);
WIRE 16 -1 (-8600 550)(-8325 550);
WIRE 16 -1 (-8600 775)(-8600 550);
WIRE 16 -1 (-8325 550)(-8050 550);
WIRE 16 -1 (-8325 775)(-8325 550);
WIRE 16 -1 (-8050 550)(-7775 550);
WIRE 16 -1 (-8050 775)(-8050 550);
WIRE 16 -1 (-7775 550)(-7500 550);
WIRE 16 -1 (-7775 775)(-7775 550);
WIRE 16 -1 (-7200 550)(-7500 550);
WIRE 16 -1 (-7500 775)(-7500 550);
WIRE 16 -1 (-7200 550)(-6925 550);
WIRE 16 -1 (-7200 775)(-7200 550);
WIRE 16 -1 (-6925 550)(-6625 550);
WIRE 16 -1 (-6925 775)(-6925 550);
WIRE 16 -1 (-6625 550)(-6325 550);
WIRE 16 -1 (-6625 775)(-6625 550);
WIRE 16 -1 (-6325 550)(-6050 550);
WIRE 16 -1 (-6325 775)(-6325 550);
WIRE 16 -1 (-6050 550)(-5775 550);
WIRE 16 -1 (-6050 775)(-6050 550);
WIRE 16 -1 (-5500 550)(-5775 550);
WIRE 16 -1 (-5775 775)(-5775 550);
WIRE 16 -1 (-5500 775)(-5500 550);
WIRE 16 -1 (-1875 725)(-1875 775);
WIRE 16 -1 (-1875 775)(-1675 775);
WIRE 16 -1 (-1325 725)(-1325 775);
WIRE 16 -1 (-1325 775)(-1475 775);
WIRE 16 -1 (-1150 3925)(-1150 3850);
WIRE 16 -1 (-1150 3850)(-1200 3850);
WIRE 16 -1 (-850 3850)(-1150 3850);
WIRE 16 -1 (-850 3850)(-850 3175);
WIRE 16 -1 (-1475 3850)(-1200 3850);
WIRE 16 -1 (-1200 3850)(-1200 3775);
WIRE 16 -1 (-1800 3850)(-1475 3850);
WIRE 16 -1 (-1475 3850)(-1475 3775);
WIRE 16 -1 (-1700 3175)(-850 3175);
WIRE 16 -1 (-1700 3175)(-1700 3025);
WIRE 16 -1 (-1800 3850)(-2100 3850);
WIRE 16 -1 (-1800 3750)(-1800 3850);
WIRE 16 -1 (-2400 3850)(-2100 3850);
WIRE 16 -1 (-2100 3850)(-2100 3750);
WIRE 16 -1 (-2450 3850)(-2400 3850);
WIRE 16 -1 (-2400 3750)(-2400 3850);
WIRE 16 -1 (-5425 3950)(-5425 4050);
WIRE 16 -1 (-8175 4450)(-8175 4300);
WIRE 16 -1 (-8175 4300)(-8050 4300);
WIRE 16 -1 (-3975 625)(-3975 525);
WIRE 16 -1 (-4575 1475)(-4575 1350);
WIRE 16 -1 (-3425 2025)(-3425 1975);
WIRE 16 -1 (-3425 2075)(-3425 2025);
WIRE 16 -1 (-3650 2025)(-3425 2025);
WIRE 16 -1 (-3425 2125)(-3425 2075);
WIRE 16 -1 (-3650 2075)(-3425 2075);
WIRE 16 -1 (-3425 2175)(-3425 2125);
WIRE 16 -1 (-3650 2125)(-3425 2125);
WIRE 16 -1 (-3425 2225)(-3425 2175);
WIRE 16 -1 (-3650 2175)(-3425 2175);
WIRE 16 -1 (-3425 2275)(-3425 2225);
WIRE 16 -1 (-3650 2225)(-3425 2225);
WIRE 16 -1 (-3425 2325)(-3425 2275);
WIRE 16 -1 (-3650 2275)(-3425 2275);
WIRE 16 -1 (-3425 2375)(-3425 2325);
WIRE 16 -1 (-3650 2325)(-3425 2325);
WIRE 16 -1 (-3425 2425)(-3425 2375);
WIRE 16 -1 (-3650 2375)(-3425 2375);
WIRE 16 -1 (-3425 2475)(-3425 2425);
WIRE 16 -1 (-3650 2425)(-3425 2425);
WIRE 16 -1 (-3425 2525)(-3425 2475);
WIRE 16 -1 (-3650 2475)(-3425 2475);
WIRE 16 -1 (-3425 2575)(-3425 2525);
WIRE 16 -1 (-3650 2525)(-3425 2525);
WIRE 16 -1 (-3425 2625)(-3425 2575);
WIRE 16 -1 (-3650 2575)(-3425 2575);
WIRE 16 -1 (-3425 2675)(-3425 2625);
WIRE 16 -1 (-3650 2625)(-3425 2625);
WIRE 16 -1 (-3425 2725)(-3425 2675);
WIRE 16 -1 (-3650 2675)(-3425 2675);
WIRE 16 -1 (-3650 2725)(-3425 2725);
WIRE 16 -1 (-2875 3225)(-2875 3200);
WIRE 16 -1 (-2400 3450)(-2400 3550);
WIRE 16 -1 (-2100 3325)(-2100 3350);
WIRE 16 -1 (-1800 3350)(-2100 3350);
WIRE 16 -1 (-2100 3550)(-2100 3350);
WIRE 16 -1 (-1800 3550)(-1800 3350);
WIRE 16 -1 (-1475 3475)(-1475 3575);
WIRE 16 -1 (-1200 3450)(-1200 3575);
WIRE 16 -1 (-6125 2075)(-6125 2325);
WIRE 16 -1 (-5425 2075)(-5425 2000);
WIRE 16 -1 (-4725 1900)(-4725 2025);
WIRE 16 -1 (-4725 2025)(-4650 2025);
WIRE 16 -1 (-5100 1550)(-5100 1400);
WIRE 16 -1 (-6825 2175)(-6825 2400);
WIRE 16 -1 (-5775 2925)(-5775 2775);
WIRE 16 -1 (-4650 2925)(-5775 2925);
WIRE 16 -1 (-5475 3425)(-5475 3325);
WIRE 16 -1 (-6950 4000)(-6950 3950);
WIRE 16 -1 (-6600 3950)(-6600 4000);
WIRE 16 -1 (-6225 3950)(-6225 4000);
WIRE 16 -1 (-5850 3950)(-5850 4000);
WIRE 16 -1 (-1700 1000)(-1700 1200);
WIRE 16 -1 (-7300 4025)(-7300 3900);
WIRE 16 -1 (-7600 4025)(-7600 3900);
WIRE 16 682 (-1050 4750)(-2375 4750);
WIRE 16 682 (-1050 4250)(-1050 4750);
WIRE 16 682 (-2375 4750)(-2375 4250);
WIRE 16 682 (-2375 4250)(-1050 4250);
WIRE 3 682 (-4700 3975)(-4375 3975);
WIRE 3 682 (-4700 4275)(-4700 3975);
WIRE 3 682 (-4375 3975)(-4375 4275);
WIRE 3 682 (-4375 4275)(-4700 4275);
WIRE 16 -1 (-4650 2825)(-6400 2825);
FORCEPROP 2 LAST SIG_NAME FM_PVPP_PVDDQ_CPU0_EN_DEF
J 0
(-5501 2850);
DISPLAY 0.617021 (-5501 2850);
PAINT ORANGE (-5501 2850);
FORCEPROP 2 LASTPROP $XRERR UNIQUE?
J 0
(-5741 2850);
DISPLAY 0.638298 (-5741 2850);
PAINT MONO (-5741 2850);
DISPLAY INVISIBLE (-5741 2850);
WIRE 16 2175 (-4750 4375)(-3525 4375);
WIRE 16 2175 (-3525 4375)(-3525 4000);
WIRE 16 2175 (-4750 4000)(-4750 4375);
WIRE 16 2175 (-4750 4000)(-3525 4000);
WIRE 16 2175 (-1075 3125)(-1075 1025);
WIRE 16 2175 (-1775 3125)(-1075 3125);
WIRE 16 2175 (-1775 1025)(-1075 1025);
WIRE 16 2175 (-1775 1025)(-1775 3125);
WIRE 16 2175 (-5200 400)(-8750 400);
WIRE 16 2175 (-5200 1250)(-5200 400);
WIRE 16 2175 (-8750 400)(-8750 1250);
WIRE 16 2175 (-8750 1250)(-5200 1250);
WIRE 16 -1 (-1350 1675)(-1350 1600);
WIRE 16 -1 (-1700 1750)(-1700 1600);
WIRE 16 -1 (-1350 1600)(-1700 1600);
WIRE 16 -1 (-1700 1550)(-1700 1400);
WIRE 16 -1 (-1700 1600)(-1700 1550);
WIRE 16 -1 (-2250 2450)(-2300 2450);
WIRE 16 -1 (-2175 1550)(-1700 1550);
FORCEPROP 0 LAST SIG_NAME VR_FB_PVPP_DEF
J 0
(-2135 1560);
DISPLAY 0.617021 (-2135 1560);
PAINT ORANGE (-2135 1560);
FORCEPROP 2 LASTPROP $XRERR UNIQUE?
J 0
(-2375 1560);
DISPLAY 0.638298 (-2375 1560);
PAINT MONO (-2375 1560);
DISPLAY INVISIBLE (-2375 1560);
WIRE 16 -1 (-2175 1550)(-2175 2925);
WIRE 16 -1 (-2250 2450)(-2250 2825);
WIRE 16 -1 (-2500 2825)(-2250 2825);
WIRE 16 -1 (-2250 2825)(-2250 2925);
WIRE 16 -1 (-2175 2925)(-2250 2925);
WIRE 16 -1 (-3650 2925)(-2250 2925);
WIRE 16 -1 (-3975 825)(-3975 975);
WIRE 16 -1 (-3750 975)(-3975 975);
WIRE 16 -1 (-4575 1150)(-4575 975);
WIRE 16 -1 (-4575 975)(-3975 975);
FORCEPROP 2 LAST SIG_NAME PWRGD_PVPP_DEF_R
J 0
(-4485 985);
DISPLAY 0.617021 (-4485 985);
PAINT ORANGE (-4485 985);
FORCEPROP 2 LASTPROP $XRERR UNIQUE?
J 0
(-4725 985);
DISPLAY 0.638298 (-4725 985);
PAINT MONO (-4725 985);
DISPLAY INVISIBLE (-4725 985);
WIRE 16 -1 (-4575 975)(-4900 975);
WIRE 16 -1 (-4900 975)(-4900 2525);
WIRE 16 -1 (-4650 2525)(-4900 2525);
WIRE 3 682 (-5600 1350)(-5600 1850);
WIRE 3 682 (-5050 1350)(-5600 1350);
WIRE 3 682 (-5600 1850)(-5050 1850);
WIRE 3 682 (-5050 1850)(-5050 1350);
WIRE 16 -1 (-5100 2625)(-4650 2625);
WIRE 16 -1 (-5100 1750)(-5100 2625);
FORCEPROP 2 LAST SIG_NAME VR_PVPP_DEF_ISET
R 1
J 0
(-5110 2110);
DISPLAY 0.617021 (-5110 2110);
PAINT ORANGE (-5110 2110);
FORCEPROP 2 LASTPROP $XRERR UNIQUE?
J 0
(-5350 2110);
DISPLAY 0.638298 (-5350 2110);
PAINT MONO (-5350 2110);
DISPLAY INVISIBLE (-5350 2110);
WIRE 16 -1 (-7600 4300)(-7850 4300);
WIRE 16 -1 (-7600 4175)(-7600 4300);
WIRE 16 -1 (-7300 4300)(-7600 4300);
WIRE 16 -1 (-7300 4300)(-7300 4175);
WIRE 16 -1 (-6950 4300)(-7300 4300);
WIRE 16 -1 (-6950 4200)(-6950 4300);
WIRE 16 -1 (-6600 4300)(-6950 4300);
WIRE 16 -1 (-6600 4200)(-6600 4300);
WIRE 16 -1 (-6225 4300)(-6600 4300);
FORCEPROP 0 LAST SIG_NAME VR_FET_SW_P12V_STBY_PVPP_DEF
J 0
(-6260 4310);
DISPLAY 0.617021 (-6260 4310);
PAINT ORANGE (-6260 4310);
FORCEPROP 2 LASTPROP $XRERR UNIQUE?
J 0
(-6500 4310);
DISPLAY 0.638298 (-6500 4310);
PAINT MONO (-6500 4310);
DISPLAY INVISIBLE (-6500 4310);
WIRE 16 -1 (-6225 4200)(-6225 4300);
WIRE 16 -1 (-5850 4300)(-6225 4300);
WIRE 16 -1 (-5850 4200)(-5850 4300);
WIRE 16 -1 (-5425 4300)(-5850 4300);
WIRE 16 -1 (-5425 4250)(-5425 4300);
WIRE 16 -1 (-5075 4300)(-5425 4300);
WIRE 16 -1 (-5475 3625)(-5475 3750);
WIRE 16 -1 (-5475 3750)(-5075 3750);
WIRE 16 -1 (-5075 4300)(-5075 3750);
WIRE 16 -1 (-4650 3575)(-5075 3575);
WIRE 16 -1 (-5075 3750)(-5075 3575);
WIRE 16 -1 (-5075 3575)(-5075 3475);
WIRE 16 -1 (-5075 3475)(-4650 3475);
WIRE 16 -1 (-5075 3425)(-5075 3475);
WIRE 16 -1 (-4650 3425)(-5075 3425);
WIRE 16 -1 (-5075 3375)(-5075 3425);
WIRE 16 -1 (-4650 3375)(-5075 3375);
WIRE 16 -1 (-5075 3325)(-5075 3375);
WIRE 16 -1 (-4650 3325)(-5075 3325);
WIRE 16 -1 (-5075 3275)(-5075 3325);
WIRE 16 -1 (-4650 3275)(-5075 3275);
WIRE 16 -1 (-5075 3225)(-5075 3275);
WIRE 16 -1 (-4650 3225)(-5075 3225);
WIRE 16 -1 (-5075 3175)(-5075 3225);
WIRE 16 -1 (-4650 3175)(-5075 3175);
WIRE 16 -1 (-5075 3125)(-5075 3175);
WIRE 16 -1 (-4650 3125)(-5075 3125);
WIRE 16 2175 (-5525 3800)(-7750 3800);
WIRE 16 2175 (-5525 4450)(-5525 3800);
WIRE 16 2175 (-7750 3800)(-7750 4450);
WIRE 16 2175 (-7750 4450)(-5525 4450);
WIRE 16 -1 (-6125 3025)(-4650 3025);
FORCEPROP 0 LAST SIG_NAME VR_VB_PVPP_DEF
J 0
(-5735 3035);
DISPLAY 0.617021 (-5735 3035);
PAINT ORANGE (-5735 3035);
FORCEPROP 2 LASTPROP $XRERR UNIQUE?
J 0
(-5975 3035);
DISPLAY 0.638298 (-5975 3035);
PAINT MONO (-5975 3035);
DISPLAY INVISIBLE (-5975 3035);
WIRE 16 -1 (-6125 2525)(-6125 3025);
WIRE 68 -1 (-7000 3825)(-7000 4350);
WIRE 68 -1 (-7700 4350)(-7000 4350);
WIRE 68 -1 (-7700 3825)(-7000 3825);
WIRE 68 -1 (-7700 3825)(-7700 4350);
WIRE 3 682 (-1800 1500)(-1800 1100);
WIRE 3 682 (-1350 1500)(-1800 1500);
WIRE 3 682 (-1800 1100)(-1350 1100);
WIRE 3 682 (-1350 1100)(-1350 1500);
WIRE 16 -1 (-2875 3425)(-2875 3600);
FORCEPROP 2 LAST SIG_NAME VR_PVPP_DEF_SNUB
J 0
(-2860 3485);
DISPLAY 0.617021 (-2860 3485);
PAINT ORANGE (-2860 3485);
FORCEPROP 2 LASTPROP $XRERR UNIQUE?
J 0
(-3100 3485);
DISPLAY 0.638298 (-3100 3485);
PAINT MONO (-3100 3485);
DISPLAY INVISIBLE (-3100 3485);
WIRE 16 -1 (-1350 1875)(-1350 2425);
FORCEPROP 0 LAST SIG_NAME VR_COMP_PVPP_DEF
R 1
J 0
(-1360 1910);
DISPLAY 0.617021 (-1360 1910);
PAINT ORANGE (-1360 1910);
FORCEPROP 2 LASTPROP $XRERR UNIQUE?
J 0
(-1600 1910);
DISPLAY 0.638298 (-1600 1910);
PAINT MONO (-1600 1910);
DISPLAY INVISIBLE (-1600 1910);
WIRE 16 -1 (-2950 975)(-3550 975);
FORCEPROP 2 LAST SIG_NAME PWRGD_PVPP_DEF
J 0
(-3410 985);
DISPLAY 0.617021 (-3410 985);
PAINT ORANGE (-3410 985);
WIRE 16 -1 (-3650 2825)(-3350 2825);
WIRE 16 -1 (-3350 2825)(-2700 2825);
WIRE 16 -1 (-3350 2450)(-3350 2825);
FORCEPROP 0 LAST SIG_NAME VR_COMP_PVPP_DEF_3
J 0
(-3260 2835);
DISPLAY 0.617021 (-3260 2835);
PAINT ORANGE (-3260 2835);
FORCEPROP 2 LASTPROP $XRERR UNIQUE?
J 0
(-3500 2835);
DISPLAY 0.638298 (-3500 2835);
PAINT MONO (-3500 2835);
DISPLAY INVISIBLE (-3500 2835);
WIRE 16 -1 (-3300 2450)(-3350 2450);
WIRE 16 -1 (-3650 3025)(-3375 3025);
WIRE 16 -1 (-3375 3025)(-3375 3125);
WIRE 16 -1 (-3650 3125)(-3375 3125);
WIRE 16 -1 (-3650 3175)(-3375 3175);
WIRE 16 -1 (-3375 3125)(-3375 3175);
WIRE 16 -1 (-3650 3225)(-3375 3225);
WIRE 16 -1 (-3375 3175)(-3375 3225);
WIRE 16 -1 (-3650 3275)(-3375 3275);
WIRE 16 -1 (-3375 3225)(-3375 3275);
WIRE 16 -1 (-3650 3325)(-3375 3325);
WIRE 16 -1 (-3375 3275)(-3375 3325);
WIRE 16 -1 (-3650 3375)(-3375 3375);
WIRE 16 -1 (-3375 3325)(-3375 3375);
WIRE 16 -1 (-3650 3425)(-3375 3425);
WIRE 16 -1 (-3375 3375)(-3375 3425);
WIRE 16 -1 (-2875 3800)(-2875 3850);
WIRE 16 -1 (-2650 3850)(-2875 3850);
WIRE 16 -1 (-3650 3475)(-3375 3475);
WIRE 16 -1 (-3375 3425)(-3375 3475);
WIRE 16 -1 (-3375 3475)(-3375 3850);
WIRE 16 -1 (-3375 3850)(-2875 3850);
FORCEPROP 2 LAST SIG_NAME VR_PVPP_DEF_PHASE
J 0
(-3360 3860);
DISPLAY 0.617021 (-3360 3860);
PAINT ORANGE (-3360 3860);
FORCEPROP 2 LASTPROP $XRERR UNIQUE?
J 0
(-3600 3860);
DISPLAY 0.638298 (-3600 3860);
PAINT MONO (-3600 3860);
DISPLAY INVISIBLE (-3600 3860);
WIRE 16 -1 (-3375 4200)(-3375 3850);
WIRE 16 -1 (-3575 4200)(-3375 4200);
WIRE 16 -1 (-1350 2625)(-1350 2675);
WIRE 16 -1 (-1700 1950)(-1700 2675);
FORCEPROP 0 LAST SIG_NAME VSENSE_PVPP_DEF
R 1
J 0
(-1710 2035);
DISPLAY 0.617021 (-1710 2035);
PAINT ORANGE (-1710 2035);
FORCEPROP 2 LASTPROP $XRERR UNIQUE?
J 0
(-1950 2035);
DISPLAY 0.638298 (-1950 2035);
PAINT MONO (-1950 2035);
DISPLAY INVISIBLE (-1950 2035);
WIRE 16 -1 (-1350 2675)(-1700 2675);
WIRE 16 -1 (-1700 2825)(-1700 2675);
WIRE 16 -1 (-2500 2450)(-3100 2450);
FORCEPROP 0 LAST SIG_NAME VR_COMP_RC_PVPP_DEF
J 0
(-3010 2460);
DISPLAY 0.617021 (-3010 2460);
PAINT ORANGE (-3010 2460);
FORCEPROP 2 LASTPROP $XRERR UNIQUE?
J 0
(-3250 2460);
DISPLAY 0.638298 (-3250 2460);
PAINT MONO (-3250 2460);
DISPLAY INVISIBLE (-3250 2460);
WIRE 16 -1 (-3775 4175)(-4400 4175);
FORCEPROP 2 LAST SIG_NAME VR_PVPP_DEF_BOOT_R
J 0
(-4305 4185);
DISPLAY 0.617021 (-4305 4185);
PAINT ORANGE (-4305 4185);
FORCEPROP 2 LASTPROP $XRERR UNIQUE?
J 0
(-4545 4185);
DISPLAY 0.638298 (-4545 4185);
PAINT MONO (-4545 4185);
DISPLAY INVISIBLE (-4545 4185);
WIRE 16 -1 (-3775 4175)(-3775 4200);
WIRE 16 -1 (-3600 3575)(-3650 3575);
WIRE 16 -1 (-3600 3900)(-3600 3575);
WIRE 16 -1 (-4650 3900)(-3600 3900);
WIRE 16 -1 (-4650 4175)(-4650 3900);
FORCEPROP 2 LAST SIG_NAME VR_PVPP_DEF_BOOT
J 0
(-4560 3935);
DISPLAY 0.617021 (-4560 3935);
PAINT ORANGE (-4560 3935);
FORCEPROP 2 LASTPROP $XRERR UNIQUE?
J 0
(-4800 3935);
DISPLAY 0.638298 (-4800 3935);
PAINT MONO (-4800 3935);
DISPLAY INVISIBLE (-4800 3935);
WIRE 16 -1 (-4600 4175)(-4650 4175);
WIRE 16 -1 (-6825 2825)(-7825 2825);
FORCEPROP 2 LAST SIG_NAME FM_PVPP_CPU0_EN
J 0
(-7801 2850);
DISPLAY 0.617021 (-7801 2850);
PAINT ORANGE (-7801 2850);
WIRE 16 -1 (-6825 2600)(-6825 2825);
WIRE 16 -1 (-6600 2825)(-6825 2825);
WIRE 16 -1 (-5425 2725)(-5425 2275);
FORCEPROP 2 LAST SIG_NAME VR_PVPP_DEF_SS
R 1
J 0
(-5435 2285);
DISPLAY 0.617021 (-5435 2285);
PAINT ORANGE (-5435 2285);
FORCEPROP 2 LASTPROP $XRERR UNIQUE?
J 0
(-5675 2285);
DISPLAY 0.638298 (-5675 2285);
PAINT MONO (-5675 2285);
DISPLAY INVISIBLE (-5675 2285);
WIRE 16 -1 (-4650 2725)(-5425 2725);
WIRE 3 682 (-6350 2625)(-6350 2150);
WIRE 3 682 (-5800 2625)(-6350 2625);
WIRE 3 682 (-6350 2150)(-5800 2150);
WIRE 3 682 (-5800 2150)(-5800 2625);
DOT 1 (-7300 4300);
DOT 1 (-7600 4300);
DOT 1 (-5075 3750);
DOT 1 (-3375 3425);
DOT 1 (-6925 1050);
DOT 1 (-5075 3325);
DOT 1 (-5425 4300);
DOT 1 (-5075 3175);
DOT 1 (-2875 3850);
DOT 1 (-2400 3850);
DOT 1 (-2250 2825);
DOT 1 (-2250 2925);
DOT 1 (-1700 2675);
DOT 1 (-1700 1600);
DOT 1 (-3975 975);
DOT 1 (-8050 1050);
DOT 1 (-8600 1050);
DOT 1 (-8325 1050);
DOT 1 (-1150 3850);
DOT 1 (-1475 3850);
DOT 1 (-3375 3850);
DOT 1 (-3375 3475);
DOT 1 (-3375 3375);
DOT 1 (-3375 3325);
DOT 1 (-3375 3275);
DOT 1 (-3375 3225);
DOT 1 (-3375 3175);
DOT 1 (-3375 3125);
DOT 1 (-3350 2825);
DOT 1 (-3425 2675);
DOT 1 (-3425 2625);
DOT 1 (-3425 2575);
DOT 1 (-3425 2475);
DOT 1 (-3425 2525);
DOT 1 (-3425 2425);
DOT 1 (-3425 2375);
DOT 1 (-3425 2325);
DOT 1 (-3425 2225);
DOT 1 (-3425 2275);
DOT 1 (-3425 2175);
DOT 1 (-3425 2125);
DOT 1 (-3425 2075);
DOT 1 (-3425 2025);
DOT 1 (-5850 4300);
DOT 1 (-6225 4300);
DOT 1 (-5075 3575);
DOT 1 (-5075 3475);
DOT 1 (-5075 3375);
DOT 1 (-5075 3425);
DOT 1 (-5075 3275);
DOT 1 (-5075 3225);
DOT 1 (-4575 975);
DOT 1 (-5775 1050);
DOT 1 (-6825 2825);
DOT 1 (-7200 1050);
DOT 1 (-7500 1050);
DOT 1 (-7775 1050);
DOT 1 (-6950 4300);
DOT 1 (-1700 1550);
DOT 1 (-6600 4300);
DOT 1 (-6325 1050);
DOT 1 (-2100 3850);
DOT 1 (-2100 3350);
DOT 1 (-1800 3850);
DOT 1 (-1200 3850);
DOT 1 (-6050 1050);
DOT 1 (-8600 550);
DOT 1 (-8325 550);
DOT 1 (-6325 550);
DOT 1 (-6925 550);
DOT 1 (-8050 550);
DOT 1 (-5775 550);
DOT 1 (-6050 550);
DOT 1 (-7500 550);
DOT 1 (-6625 550);
DOT 1 (-7200 550);
DOT 1 (-7775 550);
DOT 1 (-6625 1050);
FORCENOTE
TP FAB1 CHANGE CAP 0422
(-6425 2075) 0;
DISPLAY LEFT (-6425 2075);
DISPLAY 1.021277 (-6425 2075);
PAINT RED (-6425 2075);
FORCENOTE
(0.4V/MS)
(-5795 2130) 0;
DISPLAY LEFT (-5795 2130);
PAINT PURPLE (-5795 2130);
FORCENOTE
12A OC
(-5545 1630) 0;
DISPLAY LEFT (-5545 1630);
PAINT PURPLE (-5545 1630);
FORCENOTE
TP FAB3 CHANGE RES 0823
(-5775 1300) 0;
DISPLAY LEFT (-5775 1300);
DISPLAY 0.638298 (-5775 1300);
PAINT RED (-5775 1300);
FORCENOTE
PUT TOGETHER
(-7700 4375) 0;
DISPLAY LEFT (-7700 4375);
DISPLAY 0.808511 (-7700 4375);
PAINT PURPLE (-7700 4375);
FORCENOTE
6.25MS
(-5770 2180) 0;
DISPLAY LEFT (-5770 2180);
PAINT PURPLE (-5770 2180);
FORCENOTE
VOUT = 2.5V
(-2350 4675) 0;
DISPLAY LEFT (-2350 4675);
DISPLAY 1.021277 (-2350 4675);
PAINT PURPLE (-2350 4675);
FORCENOTE
RIPPLE GUIDELINE = +/- 1.0%
(-2350 4625) 0;
DISPLAY LEFT (-2350 4625);
DISPLAY 1.021277 (-2350 4625);
PAINT PURPLE (-2350 4625);
FORCENOTE
AC & RIPPLE TOL = +3.5%, -7.3%
(-2350 4525) 0;
DISPLAY LEFT (-2350 4525);
DISPLAY 1.021277 (-2350 4525);
PAINT PURPLE (-2350 4525);
FORCENOTE
IOUT TDC = 7.21A (INCLUDED CPU PVPP)
(-2350 4475) 0;
DISPLAY LEFT (-2350 4475);
DISPLAY 1.021277 (-2350 4475);
PAINT PURPLE (-2350 4475);
FORCENOTE
IOUT PK = 10.1A (INCLUDED CPU PVPP)
(-2350 4425) 0;
DISPLAY LEFT (-2350 4425);
DISPLAY 1.021277 (-2350 4425);
PAINT PURPLE (-2350 4425);
FORCENOTE
IOUT DI/DT = 21.5A/US
(-2350 4325) 0;
DISPLAY LEFT (-2350 4325);
DISPLAY 1.021277 (-2350 4325);
PAINT PURPLE (-2350 4325);
FORCENOTE
IOUT STEP = 5.3A
(-2350 4375) 0;
DISPLAY LEFT (-2350 4375);
DISPLAY 1.021277 (-2350 4375);
PAINT PURPLE (-2350 4375);
FORCENOTE
SW FREQ =  500KHZ
(-2350 4275) 0;
DISPLAY LEFT (-2350 4275);
DISPLAY 1.021277 (-2350 4275);
PAINT PURPLE (-2350 4275);
FORCENOTE
TOP LAYER
(-4075 4425) 0;
DISPLAY LEFT (-4075 4425);
DISPLAY 1.042553 (-4075 4425);
PAINT PURPLE (-4075 4425);
FORCENOTE
ROOM = PVPP_DEF_VR
(-7770 257) 0;
DISPLAY LEFT (-7770 257);
DISPLAY 1.021277 (-7770 257);
PAINT PURPLE (-7770 257);
FORCENOTE
BOM_COST: PVPP_DEF_VR
(-7761 159) 0;
DISPLAY LEFT (-7761 159);
DISPLAY 1.021277 (-7761 159);
PAINT PURPLE (-7761 159);
FORCENOTE
PLACE ON
(-4450 4425) 0;
DISPLAY LEFT (-4450 4425);
DISPLAY 1.042553 (-4450 4425);
PAINT PURPLE (-4450 4425);
FORCENOTE
TP FAB1 CHANGE RES PACKAGE TO 0603
(-4725 4325) 0;
DISPLAY LEFT (-4725 4325);
DISPLAY 0.638298 (-4725 4325);
PAINT RED (-4725 4325);
FORCENOTE
SPOF
(-4750 4425) 0;
DISPLAY LEFT (-4750 4425);
DISPLAY 1.659574 (-4750 4425);
PAINT PURPLE (-4750 4425);
FORCENOTE
SPOF
(-1555 2975) 0;
DISPLAY LEFT (-1555 2975);
DISPLAY 2.340426 (-1555 2975);
PAINT PURPLE (-1555 2975);
FORCENOTE
COMPENSATION TYPE III
(-3325 2100) 0;
DISPLAY LEFT (-3325 2100);
DISPLAY 1.042553 (-3325 2100);
PAINT PURPLE (-3325 2100);
FORCENOTE
TP FAB1 CHANGE RES 0531
(-2700 1125) 0;
DISPLAY LEFT (-2700 1125);
DISPLAY 1.021277 (-2700 1125);
PAINT RED (-2700 1125);
FORCENOTE
TP FAB1 CHANGE ONE 47UF CPA TO TWO 22UF CAPS 0107
(-7900 3725) 0;
DISPLAY LEFT (-7900 3725);
DISPLAY 1.021277 (-7900 3725);
PAINT RED (-7900 3725);
FORCENOTE
CAPS TO BE PLACED BETWEEN DIMMS
(-8195 1130) 0;
DISPLAY LEFT (-8195 1130);
DISPLAY 1.021277 (-8195 1130);
PAINT PURPLE (-8195 1130);
FORCENOTE
DC TOL = +/-1.5%
(-2350 4575) 0;
DISPLAY LEFT (-2350 4575);
DISPLAY 1.021277 (-2350 4575);
PAINT PURPLE (-2350 4575);
QUIT
